FILE_TYPE = MACRO_DRAWING;
SET COLOR_WIRE YELLOW;
SET COLOR_PROP ORANGE;
SET COLOR_DOT WHITE;
SET COLOR_ARC YELLOW;
SET COLOR_BODY GREEN;
SET COLOR_NOTE PURPLE;
SET PROP_DISPLAY VALUE;
SET PAGE_NUMBER P54;
FORCEADD UNIVERSAL_POWER..1
(-150 6225);
FORCEPROP 3 LASTPIN (-150 6175) SIG_NAME PVDD18_S5_P1\g
J 0
(-140 6185);
DISPLAY 0.659574 (-140 6185);
PAINT MONO (-140 6185);
DISPLAY INVISIBLE (-140 6185);
FORCEPROP 1 LAST HDL_POWER PVDD18_S5_P1
J 1
(-150 6275);
DISPLAY 0.489362 (-150 6275);
PAINT GREEN (-150 6275);
FORCEPROP 2 LAST CDS_LIB pure_quanta_power
J 0
(-150 6225);
DISPLAY INVISIBLE (-150 6225);
FORCEPROP 1 LAST PATH I156
J 0
(-100 6250);
DISPLAY 0.872340 (-100 6250);
PAINT AQUA (-100 6250);
DISPLAY INVISIBLE (-100 6250);
FORCEADD OFFPAGE..2
R 2
(-1400 6075);
FORCEPROP 2 LAST $XR0 54 
J 0
(-1624 6075);
DISPLAY 0.638298 (-1624 6075);
PAINT MONO (-1624 6075);
FORCEPROP 2 LAST CDS_LIB standard
J 0
(-1400 6075);
DISPLAY INVISIBLE (-1400 6075);
FORCEPROP 1 LAST OFFPAGE TRUE
J 2
(-1725 5950);
DISPLAY 0.872340 (-1725 5950);
PAINT GREEN (-1725 5950);
DISPLAY INVISIBLE (-1725 5950);
FORCEPROP 1 LAST COMMENT_BODY TRUE
J 2
(-1355 5980);
DISPLAY 0.872340 (-1355 5980);
PAINT PEACH (-1355 5980);
DISPLAY INVISIBLE (-1355 5980);
FORCEPROP 2 LAST PATH I162
J 0
(-1350 6150);
DISPLAY 1.021277 (-1350 6150);
DISPLAY INVISIBLE (-1350 6150);
FORCEADD OFFPAGE..2
R 2
(-1400 6025);
FORCEPROP 2 LAST $XR0 54 
J 0
(-1624 6025);
DISPLAY 0.638298 (-1624 6025);
PAINT MONO (-1624 6025);
FORCEPROP 2 LAST CDS_LIB standard
J 0
(-1400 6025);
DISPLAY INVISIBLE (-1400 6025);
FORCEPROP 1 LAST OFFPAGE TRUE
J 2
(-1725 5900);
DISPLAY 0.872340 (-1725 5900);
PAINT GREEN (-1725 5900);
DISPLAY INVISIBLE (-1725 5900);
FORCEPROP 1 LAST COMMENT_BODY TRUE
J 2
(-1355 5930);
DISPLAY 0.872340 (-1355 5930);
PAINT PEACH (-1355 5930);
DISPLAY INVISIBLE (-1355 5930);
FORCEPROP 2 LAST PATH I163
J 0
(-1350 6100);
DISPLAY 1.021277 (-1350 6100);
DISPLAY INVISIBLE (-1350 6100);
FORCEADD OFFPAGE..2
R 2
(-1400 5975);
FORCEPROP 2 LAST $XR0 54 
J 0
(-1624 5975);
DISPLAY 0.638298 (-1624 5975);
PAINT MONO (-1624 5975);
FORCEPROP 2 LAST CDS_LIB standard
J 0
(-1400 5975);
DISPLAY INVISIBLE (-1400 5975);
FORCEPROP 1 LAST OFFPAGE TRUE
J 2
(-1725 5850);
DISPLAY 0.872340 (-1725 5850);
PAINT GREEN (-1725 5850);
DISPLAY INVISIBLE (-1725 5850);
FORCEPROP 1 LAST COMMENT_BODY TRUE
J 2
(-1355 5880);
DISPLAY 0.872340 (-1355 5880);
PAINT PEACH (-1355 5880);
DISPLAY INVISIBLE (-1355 5880);
FORCEPROP 2 LAST PATH I164
J 0
(-1350 6050);
DISPLAY 1.021277 (-1350 6050);
DISPLAY INVISIBLE (-1350 6050);
FORCEADD OFFPAGE..2
R 2
(-1400 5925);
FORCEPROP 2 LAST $XR0 54 
J 0
(-1624 5925);
DISPLAY 0.638298 (-1624 5925);
PAINT MONO (-1624 5925);
FORCEPROP 2 LAST CDS_LIB standard
J 0
(-1400 5925);
DISPLAY INVISIBLE (-1400 5925);
FORCEPROP 1 LAST OFFPAGE TRUE
J 2
(-1725 5800);
DISPLAY 0.872340 (-1725 5800);
PAINT GREEN (-1725 5800);
DISPLAY INVISIBLE (-1725 5800);
FORCEPROP 1 LAST COMMENT_BODY TRUE
J 2
(-1355 5830);
DISPLAY 0.872340 (-1355 5830);
PAINT PEACH (-1355 5830);
DISPLAY INVISIBLE (-1355 5830);
FORCEPROP 2 LAST PATH I165
J 0
(-1350 6000);
DISPLAY 1.021277 (-1350 6000);
DISPLAY INVISIBLE (-1350 6000);
FORCEADD OFFPAGE..2
R 2
(-1400 5875);
FORCEPROP 2 LAST $XR0 54 
J 0
(-1624 5875);
DISPLAY 0.638298 (-1624 5875);
PAINT MONO (-1624 5875);
FORCEPROP 2 LAST CDS_LIB standard
J 0
(-1400 5875);
DISPLAY INVISIBLE (-1400 5875);
FORCEPROP 1 LAST OFFPAGE TRUE
J 2
(-1725 5750);
DISPLAY 0.872340 (-1725 5750);
PAINT GREEN (-1725 5750);
DISPLAY INVISIBLE (-1725 5750);
FORCEPROP 1 LAST COMMENT_BODY TRUE
J 2
(-1355 5780);
DISPLAY 0.872340 (-1355 5780);
PAINT PEACH (-1355 5780);
DISPLAY INVISIBLE (-1355 5780);
FORCEPROP 2 LAST PATH I166
J 0
(-1350 5950);
DISPLAY 1.021277 (-1350 5950);
DISPLAY INVISIBLE (-1350 5950);
FORCEADD OFFPAGE..2
R 2
(-1400 5825);
FORCEPROP 2 LAST $XR0 54 
J 0
(-1624 5825);
DISPLAY 0.638298 (-1624 5825);
PAINT MONO (-1624 5825);
FORCEPROP 2 LAST CDS_LIB standard
J 0
(-1400 5825);
DISPLAY INVISIBLE (-1400 5825);
FORCEPROP 1 LAST OFFPAGE TRUE
J 2
(-1725 5700);
DISPLAY 0.872340 (-1725 5700);
PAINT GREEN (-1725 5700);
DISPLAY INVISIBLE (-1725 5700);
FORCEPROP 1 LAST COMMENT_BODY TRUE
J 2
(-1355 5730);
DISPLAY 0.872340 (-1355 5730);
PAINT PEACH (-1355 5730);
DISPLAY INVISIBLE (-1355 5730);
FORCEPROP 2 LAST PATH I168
J 0
(-1350 5900);
DISPLAY 1.021277 (-1350 5900);
DISPLAY INVISIBLE (-1350 5900);
FORCEADD OFFPAGE..2
R 2
(-1400 5775);
FORCEPROP 2 LAST $XR1 81 
J 0
(-1714 5775);
DISPLAY 0.638298 (-1714 5775);
PAINT MONO (-1714 5775);
FORCEPROP 2 LAST $XR0 54 
J 0
(-1624 5775);
DISPLAY 0.638298 (-1624 5775);
PAINT MONO (-1624 5775);
FORCEPROP 2 LAST CDS_LIB standard
J 0
(-1400 5775);
DISPLAY INVISIBLE (-1400 5775);
FORCEPROP 1 LAST OFFPAGE TRUE
J 2
(-1725 5650);
DISPLAY 0.872340 (-1725 5650);
PAINT GREEN (-1725 5650);
DISPLAY INVISIBLE (-1725 5650);
FORCEPROP 1 LAST COMMENT_BODY TRUE
J 2
(-1355 5680);
DISPLAY 0.872340 (-1355 5680);
PAINT PEACH (-1355 5680);
DISPLAY INVISIBLE (-1355 5680);
FORCEPROP 2 LAST PATH I176
J 0
(-1350 5850);
DISPLAY 1.021277 (-1350 5850);
DISPLAY INVISIBLE (-1350 5850);
FORCEADD OFFPAGE..2
R 2
(-1400 5725);
FORCEPROP 2 LAST $XR1 81 
J 0
(-1714 5725);
DISPLAY 0.638298 (-1714 5725);
PAINT MONO (-1714 5725);
FORCEPROP 2 LAST $XR0 54 
J 0
(-1624 5725);
DISPLAY 0.638298 (-1624 5725);
PAINT MONO (-1624 5725);
FORCEPROP 2 LAST CDS_LIB standard
J 0
(-1400 5725);
DISPLAY INVISIBLE (-1400 5725);
FORCEPROP 1 LAST OFFPAGE TRUE
J 2
(-1725 5600);
DISPLAY 0.872340 (-1725 5600);
PAINT GREEN (-1725 5600);
DISPLAY INVISIBLE (-1725 5600);
FORCEPROP 1 LAST COMMENT_BODY TRUE
J 2
(-1355 5630);
DISPLAY 0.872340 (-1355 5630);
PAINT PEACH (-1355 5630);
DISPLAY INVISIBLE (-1355 5630);
FORCEPROP 2 LAST PATH I177
J 0
(-1350 5800);
DISPLAY 1.021277 (-1350 5800);
DISPLAY INVISIBLE (-1350 5800);
FORCEADD OFFPAGE..2
R 2
(-1400 5675);
FORCEPROP 2 LAST $XR1 81 
J 0
(-1714 5675);
DISPLAY 0.638298 (-1714 5675);
PAINT MONO (-1714 5675);
FORCEPROP 2 LAST $XR0 54 
J 0
(-1624 5675);
DISPLAY 0.638298 (-1624 5675);
PAINT MONO (-1624 5675);
FORCEPROP 2 LAST CDS_LIB standard
J 0
(-1400 5675);
DISPLAY INVISIBLE (-1400 5675);
FORCEPROP 1 LAST OFFPAGE TRUE
J 2
(-1725 5550);
DISPLAY 0.872340 (-1725 5550);
PAINT GREEN (-1725 5550);
DISPLAY INVISIBLE (-1725 5550);
FORCEPROP 1 LAST COMMENT_BODY TRUE
J 2
(-1355 5580);
DISPLAY 0.872340 (-1355 5580);
PAINT PEACH (-1355 5580);
DISPLAY INVISIBLE (-1355 5580);
FORCEPROP 2 LAST PATH I178
J 0
(-1350 5750);
DISPLAY 1.021277 (-1350 5750);
DISPLAY INVISIBLE (-1350 5750);
FORCEADD OFFPAGE..2
R 2
(-1400 5625);
FORCEPROP 2 LAST $XR1 81 
J 0
(-1714 5625);
DISPLAY 0.638298 (-1714 5625);
PAINT MONO (-1714 5625);
FORCEPROP 2 LAST $XR0 54 
J 0
(-1624 5625);
DISPLAY 0.638298 (-1624 5625);
PAINT MONO (-1624 5625);
FORCEPROP 2 LAST CDS_LIB standard
J 0
(-1400 5625);
DISPLAY INVISIBLE (-1400 5625);
FORCEPROP 1 LAST OFFPAGE TRUE
J 2
(-1725 5500);
DISPLAY 0.872340 (-1725 5500);
PAINT GREEN (-1725 5500);
DISPLAY INVISIBLE (-1725 5500);
FORCEPROP 1 LAST COMMENT_BODY TRUE
J 2
(-1355 5530);
DISPLAY 0.872340 (-1355 5530);
PAINT PEACH (-1355 5530);
DISPLAY INVISIBLE (-1355 5530);
FORCEPROP 2 LAST PATH I179
J 0
(-1350 5700);
DISPLAY 1.021277 (-1350 5700);
DISPLAY INVISIBLE (-1350 5700);
FORCEADD SCONN8_G802M0083150RD3EU..1
(-500 3575);
FORCEPROP 1 LAST LOCATION J7
J 0
(-625 3990);
DISPLAY 0.489362 (-625 3990);
PAINT SKYBLUE (-625 3990);
FORCEPROP 0 LAST $SEC 1
J 0
(-625 4025);
DISPLAY 0.680851 (-625 4025);
PAINT MONO (-625 4025);
DISPLAY INVISIBLE (-625 4025);
FORCEPROP 0 LAST CDS_SEC 1
J 0
(-550 3950);
DISPLAY 1.021277 (-550 3950);
DISPLAY INVISIBLE (-550 3950);
FORCEPROP 0 LASTPIN (-775 3650) $PN 1
J 2
(-785 3660);
DISPLAY 0.489362 (-785 3660);
PAINT MONO (-785 3660);
FORCEPROP 0 LASTPIN (-225 3650) $PN 2
J 0
(-215 3660);
DISPLAY 0.489362 (-215 3660);
PAINT MONO (-215 3660);
FORCEPROP 0 LASTPIN (-775 3600) $PN 3
J 2
(-785 3610);
DISPLAY 0.489362 (-785 3610);
PAINT MONO (-785 3610);
FORCEPROP 0 LASTPIN (-225 3600) $PN 4
J 0
(-215 3610);
DISPLAY 0.489362 (-215 3610);
PAINT MONO (-215 3610);
FORCEPROP 0 LASTPIN (-775 3550) $PN 5
J 2
(-785 3560);
DISPLAY 0.489362 (-785 3560);
PAINT MONO (-785 3560);
FORCEPROP 0 LASTPIN (-225 3550) $PN 6
J 0
(-215 3560);
DISPLAY 0.489362 (-215 3560);
PAINT MONO (-215 3560);
FORCEPROP 0 LASTPIN (-775 3500) $PN 7
J 2
(-785 3510);
DISPLAY 0.489362 (-785 3510);
PAINT MONO (-785 3510);
FORCEPROP 0 LASTPIN (-225 3500) $PN 8
J 0
(-215 3510);
DISPLAY 0.489362 (-215 3510);
PAINT MONO (-215 3510);
FORCEPROP 2 LAST PART_TYPE SMLF
J 0
(-625 3900);
DISPLAY 1.021277 (-625 3900);
FORCEPROP 1 LAST MATERIAL IO
J 0
(-625 3716);
DISPLAY 0.489362 (-625 3716);
PAINT SKYBLUE (-625 3716);
FORCEPROP 2 LAST VALUE SCONN8_G802M0083150RD3EU
J 0
(-625 3850);
DISPLAY 0.489362 (-625 3850);
PAINT SKYBLUE (-625 3850);
FORCEPROP 1 LAST PART_NUMBER DFHD08MS351
J 0
(-625 3775);
DISPLAY 0.489362 (-625 3775);
PAINT SKYBLUE (-625 3775);
FORCEPROP 2 LAST CDS_LIB pure_quanta
J 0
(-500 3575);
DISPLAY INVISIBLE (-500 3575);
FORCEPROP 1 LAST NEEDS_NO_SIZE TRUE
J 0
(-500 3575);
DISPLAY 0.723404 (-500 3575);
PAINT GREEN (-500 3575);
DISPLAY INVISIBLE (-500 3575);
FORCEPROP 1 LAST CDS_LMAN_SYM_OUTLINE -125,125,125,-125
J 0
(-500 3575);
DISPLAY 0.468085 (-500 3575);
PAINT GREEN (-500 3575);
DISPLAY INVISIBLE (-500 3575);
FORCEPROP 1 LAST PATH I184
J 0
(-500 3575);
DISPLAY 0.723404 (-500 3575);
PAINT GREEN (-500 3575);
DISPLAY INVISIBLE (-500 3575);
FORCEADD GENOA_SP5..20
(-4650 3750);
FORCEPROP 1 LAST LOCATION U26
J 0
(-5250 6350);
DISPLAY 0.489362 (-5250 6350);
PAINT SKYBLUE (-5250 6350);
FORCEPROP 0 LAST $SEC 20
J 0
(-5225 6525);
DISPLAY 0.680851 (-5225 6525);
PAINT MONO (-5225 6525);
DISPLAY INVISIBLE (-5225 6525);
FORCEPROP 0 LAST CDS_SEC 20
J 0
(-5200 6250);
DISPLAY 1.021277 (-5200 6250);
DISPLAY INVISIBLE (-5200 6250);
FORCEPROP 0 LASTPIN (-3900 5125) $PN A68
J 0
(-3890 5135);
DISPLAY 0.489362 (-3890 5135);
PAINT MONO (-3890 5135);
FORCEPROP 0 LASTPIN (-3900 6025) $PN C32
J 0
(-3890 6035);
DISPLAY 0.489362 (-3890 6035);
PAINT MONO (-3890 6035);
FORCEPROP 0 LASTPIN (-3900 5975) $PN A34
J 0
(-3890 5985);
DISPLAY 0.489362 (-3890 5985);
PAINT MONO (-3890 5985);
FORCEPROP 0 LASTPIN (-3900 5925) $PN C33
J 0
(-3890 5935);
DISPLAY 0.489362 (-3890 5935);
PAINT MONO (-3890 5935);
FORCEPROP 0 LASTPIN (-3900 5875) $PN D33
J 0
(-3890 5885);
DISPLAY 0.489362 (-3890 5885);
PAINT MONO (-3890 5885);
FORCEPROP 0 LASTPIN (-3900 5825) $PN A33
J 0
(-3890 5835);
DISPLAY 0.489362 (-3890 5835);
PAINT MONO (-3890 5835);
FORCEPROP 0 LASTPIN (-3900 5775) $PN A32
J 0
(-3890 5785);
DISPLAY 0.489362 (-3890 5785);
PAINT MONO (-3890 5785);
FORCEPROP 0 LASTPIN (-3900 5725) $PN D32
J 0
(-3890 5735);
DISPLAY 0.489362 (-3890 5735);
PAINT MONO (-3890 5735);
FORCEPROP 0 LASTPIN (-3900 4475) $PN C63
J 0
(-3890 4485);
DISPLAY 0.489362 (-3890 4485);
PAINT MONO (-3890 4485);
FORCEPROP 0 LASTPIN (-3900 4425) $PN C62
J 0
(-3890 4435);
DISPLAY 0.489362 (-3890 4435);
PAINT MONO (-3890 4435);
FORCEPROP 0 LASTPIN (-3900 4375) $PN A63
J 0
(-3890 4385);
DISPLAY 0.489362 (-3890 4385);
PAINT MONO (-3890 4385);
FORCEPROP 0 LASTPIN (-3900 4325) $PN A62
J 0
(-3890 4335);
DISPLAY 0.489362 (-3890 4335);
PAINT MONO (-3890 4335);
FORCEPROP 0 LASTPIN (-5400 2775) $PN C70
J 2
(-5410 2785);
DISPLAY 0.489362 (-5410 2785);
PAINT MONO (-5410 2785);
FORCEPROP 0 LASTPIN (-5400 2725) $PN B69
J 2
(-5410 2735);
DISPLAY 0.489362 (-5410 2735);
PAINT MONO (-5410 2735);
FORCEPROP 0 LASTPIN (-5400 2675) $PN D68
J 2
(-5410 2685);
DISPLAY 0.489362 (-5410 2685);
PAINT MONO (-5410 2685);
FORCEPROP 0 LASTPIN (-5400 3325) $PN B66
J 2
(-5410 3335);
DISPLAY 0.489362 (-5410 3335);
PAINT MONO (-5410 3335);
FORCEPROP 0 LASTPIN (-5400 4525) $PN C16
J 2
(-5410 4535);
DISPLAY 0.489362 (-5410 4535);
PAINT MONO (-5410 4535);
FORCEPROP 0 LASTPIN (-5400 5925) $PN C22
J 2
(-5410 5935);
DISPLAY 0.489362 (-5410 5935);
PAINT MONO (-5410 5935);
FORCEPROP 0 LASTPIN (-5400 5875) $PN DG72
J 2
(-5410 5885);
DISPLAY 0.489362 (-5410 5885);
PAINT MONO (-5410 5885);
FORCEPROP 0 LASTPIN (-3900 5025) $PN A69
J 0
(-3890 5035);
DISPLAY 0.489362 (-3890 5035);
PAINT MONO (-3890 5035);
FORCEPROP 0 LASTPIN (-5400 1375) $PN DH8
J 2
(-5410 1385);
DISPLAY 0.489362 (-5410 1385);
PAINT MONO (-5410 1385);
FORCEPROP 0 LASTPIN (-5400 3225) $PN DJ55
J 2
(-5410 3235);
DISPLAY 0.489362 (-5410 3235);
PAINT MONO (-5410 3235);
FORCEPROP 0 LASTPIN (-5400 3175) $PN DJ56
J 2
(-5410 3185);
DISPLAY 0.489362 (-5410 3185);
PAINT MONO (-5410 3185);
FORCEPROP 0 LASTPIN (-5400 5125) $PN DJ71
J 2
(-5410 5135);
DISPLAY 0.489362 (-5410 5135);
PAINT MONO (-5410 5135);
FORCEPROP 0 LASTPIN (-5400 5075) $PN DH71
J 2
(-5410 5085);
DISPLAY 0.489362 (-5410 5085);
PAINT MONO (-5410 5085);
FORCEPROP 0 LASTPIN (-5400 3025) $PN C19
J 2
(-5410 3035);
DISPLAY 0.489362 (-5410 3035);
PAINT MONO (-5410 3035);
FORCEPROP 0 LASTPIN (-5400 2975) $PN C68
J 2
(-5410 2985);
DISPLAY 0.489362 (-5410 2985);
PAINT MONO (-5410 2985);
FORCEPROP 0 LASTPIN (-5400 2925) $PN DH73
J 2
(-5410 2935);
DISPLAY 0.489362 (-5410 2935);
PAINT MONO (-5410 2935);
FORCEPROP 0 LASTPIN (-5400 2875) $PN DH10
J 2
(-5410 2885);
DISPLAY 0.489362 (-5410 2885);
PAINT MONO (-5410 2885);
FORCEPROP 0 LASTPIN (-5400 5775) $PN A23
J 2
(-5410 5785);
DISPLAY 0.489362 (-5410 5785);
PAINT MONO (-5410 5785);
FORCEPROP 0 LASTPIN (-5400 5575) $PN DJ72
J 2
(-5410 5585);
DISPLAY 0.489362 (-5410 5585);
PAINT MONO (-5410 5585);
FORCEPROP 0 LASTPIN (-5400 5725) $PN A22
J 2
(-5410 5735);
DISPLAY 0.489362 (-5410 5735);
PAINT MONO (-5410 5735);
FORCEPROP 0 LASTPIN (-5400 5525) $PN DH72
J 2
(-5410 5535);
DISPLAY 0.489362 (-5410 5535);
PAINT MONO (-5410 5535);
FORCEPROP 0 LASTPIN (-5400 5675) $PN B21
J 2
(-5410 5685);
DISPLAY 0.489362 (-5410 5685);
PAINT MONO (-5410 5685);
FORCEPROP 0 LASTPIN (-5400 5475) $PN DG73
J 2
(-5410 5485);
DISPLAY 0.489362 (-5410 5485);
PAINT MONO (-5410 5485);
FORCEPROP 0 LASTPIN (-5400 4675) $PN B17
J 2
(-5410 4685);
DISPLAY 0.489362 (-5410 4685);
PAINT MONO (-5410 4685);
FORCEPROP 0 LASTPIN (-5400 4775) $PN C17
J 2
(-5410 4785);
DISPLAY 0.489362 (-5410 4785);
PAINT MONO (-5410 4785);
FORCEPROP 0 LASTPIN (-5400 4825) $PN C18
J 2
(-5410 4835);
DISPLAY 0.489362 (-5410 4835);
PAINT MONO (-5410 4835);
FORCEPROP 0 LASTPIN (-3900 3375) $PN AA50
J 0
(-3890 3385);
DISPLAY 0.489362 (-3890 3385);
PAINT MONO (-3890 3385);
FORCEPROP 0 LASTPIN (-3900 3325) $PN CJ28
J 0
(-3890 3335);
DISPLAY 0.489362 (-3890 3335);
PAINT MONO (-3890 3335);
FORCEPROP 0 LASTPIN (-3900 3275) $PN CJ48
J 0
(-3890 3285);
DISPLAY 0.489362 (-3890 3285);
PAINT MONO (-3890 3285);
FORCEPROP 0 LASTPIN (-3900 3225) $PN AA30
J 0
(-3890 3235);
DISPLAY 0.489362 (-3890 3235);
PAINT MONO (-3890 3235);
FORCEPROP 0 LASTPIN (-3900 3175) $PN AA52
J 0
(-3890 3185);
DISPLAY 0.489362 (-3890 3185);
PAINT MONO (-3890 3185);
FORCEPROP 0 LASTPIN (-3900 3125) $PN CJ26
J 0
(-3890 3135);
DISPLAY 0.489362 (-3890 3135);
PAINT MONO (-3890 3135);
FORCEPROP 0 LASTPIN (-3900 3075) $PN CJ50
J 0
(-3890 3085);
DISPLAY 0.489362 (-3890 3085);
PAINT MONO (-3890 3085);
FORCEPROP 0 LASTPIN (-3900 3025) $PN AA27
J 0
(-3890 3035);
DISPLAY 0.489362 (-3890 3035);
PAINT MONO (-3890 3035);
FORCEPROP 0 LASTPIN (-3900 2975) $PN AA48
J 0
(-3890 2985);
DISPLAY 0.489362 (-3890 2985);
PAINT MONO (-3890 2985);
FORCEPROP 0 LASTPIN (-3900 2925) $PN CK30
J 0
(-3890 2935);
DISPLAY 0.489362 (-3890 2935);
PAINT MONO (-3890 2935);
FORCEPROP 0 LASTPIN (-3900 2875) $PN CJ47
J 0
(-3890 2885);
DISPLAY 0.489362 (-3890 2885);
PAINT MONO (-3890 2885);
FORCEPROP 0 LASTPIN (-3900 2825) $PN AA28
J 0
(-3890 2835);
DISPLAY 0.489362 (-3890 2835);
PAINT MONO (-3890 2835);
FORCEPROP 0 LASTPIN (-3900 2075) $PN AA25
J 0
(-3890 2085);
DISPLAY 0.489362 (-3890 2085);
PAINT MONO (-3890 2085);
FORCEPROP 0 LASTPIN (-3900 2725) $PN AA51
J 0
(-3890 2735);
DISPLAY 0.489362 (-3890 2735);
PAINT MONO (-3890 2735);
FORCEPROP 0 LASTPIN (-3900 2675) $PN CJ27
J 0
(-3890 2685);
DISPLAY 0.489362 (-3890 2685);
PAINT MONO (-3890 2685);
FORCEPROP 0 LASTPIN (-3900 2625) $PN CJ49
J 0
(-3890 2635);
DISPLAY 0.489362 (-3890 2635);
PAINT MONO (-3890 2635);
FORCEPROP 0 LASTPIN (-3900 2575) $PN Y30
J 0
(-3890 2585);
DISPLAY 0.489362 (-3890 2585);
PAINT MONO (-3890 2585);
FORCEPROP 0 LASTPIN (-3900 2525) $PN AA53
J 0
(-3890 2535);
DISPLAY 0.489362 (-3890 2535);
PAINT MONO (-3890 2535);
FORCEPROP 0 LASTPIN (-3900 2475) $PN CJ25
J 0
(-3890 2485);
DISPLAY 0.489362 (-3890 2485);
PAINT MONO (-3890 2485);
FORCEPROP 0 LASTPIN (-3900 2425) $PN CJ51
J 0
(-3890 2435);
DISPLAY 0.489362 (-3890 2435);
PAINT MONO (-3890 2435);
FORCEPROP 0 LASTPIN (-3900 2375) $PN AA26
J 0
(-3890 2385);
DISPLAY 0.489362 (-3890 2385);
PAINT MONO (-3890 2385);
FORCEPROP 0 LASTPIN (-3900 2325) $PN Y47
J 0
(-3890 2335);
DISPLAY 0.489362 (-3890 2335);
PAINT MONO (-3890 2335);
FORCEPROP 0 LASTPIN (-3900 2275) $PN CK29
J 0
(-3890 2285);
DISPLAY 0.489362 (-3890 2285);
PAINT MONO (-3890 2285);
FORCEPROP 0 LASTPIN (-3900 2225) $PN CK47
J 0
(-3890 2235);
DISPLAY 0.489362 (-3890 2235);
PAINT MONO (-3890 2235);
FORCEPROP 0 LASTPIN (-3900 2175) $PN Y29
J 0
(-3890 2185);
DISPLAY 0.489362 (-3890 2185);
PAINT MONO (-3890 2185);
FORCEPROP 0 LASTPIN (-3900 1975) $PN AA24
J 0
(-3890 1985);
DISPLAY 0.489362 (-3890 1985);
PAINT MONO (-3890 1985);
FORCEPROP 0 LASTPIN (-3900 4125) $PN AA46
J 0
(-3890 4135);
DISPLAY 0.489362 (-3890 4135);
PAINT MONO (-3890 4135);
FORCEPROP 0 LASTPIN (-3900 4075) $PN CJ30
J 0
(-3890 4085);
DISPLAY 0.489362 (-3890 4085);
PAINT MONO (-3890 4085);
FORCEPROP 0 LASTPIN (-3900 4025) $PN CJ46
J 0
(-3890 4035);
DISPLAY 0.489362 (-3890 4035);
PAINT MONO (-3890 4035);
FORCEPROP 0 LASTPIN (-3900 3975) $PN Y46
J 0
(-3890 3985);
DISPLAY 0.489362 (-3890 3985);
PAINT MONO (-3890 3985);
FORCEPROP 0 LASTPIN (-3900 3475) $PN AA49
J 0
(-3890 3485);
DISPLAY 0.489362 (-3890 3485);
PAINT MONO (-3890 3485);
FORCEPROP 0 LASTPIN (-3900 3825) $PN AA47
J 0
(-3890 3835);
DISPLAY 0.489362 (-3890 3835);
PAINT MONO (-3890 3835);
FORCEPROP 0 LASTPIN (-3900 3775) $PN CJ29
J 0
(-3890 3785);
DISPLAY 0.489362 (-3890 3785);
PAINT MONO (-3890 3785);
FORCEPROP 0 LASTPIN (-3900 3725) $PN AA29
J 0
(-3890 3735);
DISPLAY 0.489362 (-3890 3735);
PAINT MONO (-3890 3735);
FORCEPROP 0 LASTPIN (-3900 3675) $PN CJ52
J 0
(-3890 3685);
DISPLAY 0.489362 (-3890 3685);
PAINT MONO (-3890 3685);
FORCEPROP 0 LASTPIN (-3900 3625) $PN AA23
J 0
(-3890 3635);
DISPLAY 0.489362 (-3890 3635);
PAINT MONO (-3890 3635);
FORCEPROP 0 LASTPIN (-3900 3575) $PN CJ53
J 0
(-3890 3585);
DISPLAY 0.489362 (-3890 3585);
PAINT MONO (-3890 3585);
FORCEPROP 0 LASTPIN (-3900 1375) $PN W31
J 0
(-3890 1385);
DISPLAY 0.489362 (-3890 1385);
PAINT MONO (-3890 1385);
FORCEPROP 0 LASTPIN (-5400 4075) $PN B60
J 2
(-5410 4085);
DISPLAY 0.489362 (-5410 4085);
PAINT MONO (-5410 4085);
FORCEPROP 0 LASTPIN (-5400 4025) $PN CJ24
J 2
(-5410 4035);
DISPLAY 0.489362 (-5410 4035);
PAINT MONO (-5410 4035);
FORCEPROP 0 LASTPIN (-5400 3975) $PN CK46
J 2
(-5410 3985);
DISPLAY 0.489362 (-5410 3985);
PAINT MONO (-5410 3985);
FORCEPROP 0 LASTPIN (-5400 3925) $PN E32
J 2
(-5410 3935);
DISPLAY 0.489362 (-5410 3935);
PAINT MONO (-5410 3935);
FORCEPROP 0 LASTPIN (-5400 3825) $PN B58
J 2
(-5410 3835);
DISPLAY 0.489362 (-5410 3835);
PAINT MONO (-5410 3835);
FORCEPROP 0 LASTPIN (-5400 3775) $PN D7
J 2
(-5410 3785);
DISPLAY 0.489362 (-5410 3785);
PAINT MONO (-5410 3785);
FORCEPROP 0 LASTPIN (-5400 3475) $PN B61
J 2
(-5410 3485);
DISPLAY 0.489362 (-5410 3485);
PAINT MONO (-5410 3485);
FORCEPROP 0 LASTPIN (-3900 4975) $PN DJ9
J 0
(-3890 4985);
DISPLAY 0.489362 (-3890 4985);
PAINT MONO (-3890 4985);
FORCEPROP 0 LASTPIN (-5400 4625) $PN A16
J 2
(-5410 4635);
DISPLAY 0.489362 (-5410 4635);
PAINT MONO (-5410 4635);
FORCEPROP 0 LASTPIN (-5400 4725) $PN A17
J 2
(-5410 4735);
DISPLAY 0.489362 (-5410 4735);
PAINT MONO (-5410 4735);
FORCEPROP 0 LASTPIN (-3900 1875) $PN DJ33
J 0
(-3890 1885);
DISPLAY 0.489362 (-3890 1885);
PAINT MONO (-3890 1885);
FORCEPROP 0 LASTPIN (-3900 1775) $PN DG34
J 0
(-3890 1785);
DISPLAY 0.489362 (-3890 1785);
PAINT MONO (-3890 1785);
FORCEPROP 0 LASTPIN (-3900 1825) $PN DF34
J 0
(-3890 1835);
DISPLAY 0.489362 (-3890 1835);
PAINT MONO (-3890 1835);
FORCEPROP 0 LASTPIN (-3900 1675) $PN DG35
J 0
(-3890 1685);
DISPLAY 0.489362 (-3890 1685);
PAINT MONO (-3890 1685);
FORCEPROP 0 LASTPIN (-3900 1725) $PN DJ34
J 0
(-3890 1735);
DISPLAY 0.489362 (-3890 1735);
PAINT MONO (-3890 1735);
FORCEPROP 0 LASTPIN (-3900 1575) $PN DH33
J 0
(-3890 1585);
DISPLAY 0.489362 (-3890 1585);
PAINT MONO (-3890 1585);
FORCEPROP 0 LASTPIN (-3900 1625) $PN DJ32
J 0
(-3890 1635);
DISPLAY 0.489362 (-3890 1635);
PAINT MONO (-3890 1635);
FORCEPROP 0 LASTPIN (-5400 2175) $PN DH3
J 2
(-5410 2185);
DISPLAY 0.489362 (-5410 2185);
PAINT MONO (-5410 2185);
FORCEPROP 0 LASTPIN (-5400 2075) $PN C74
J 2
(-5410 2085);
DISPLAY 0.489362 (-5410 2085);
PAINT MONO (-5410 2085);
FORCEPROP 0 LASTPIN (-5400 2125) $PN BP53
J 2
(-5410 2135);
DISPLAY 0.489362 (-5410 2135);
PAINT MONO (-5410 2135);
FORCEPROP 0 LASTPIN (-5400 2225) $PN C2
J 2
(-5410 2235);
DISPLAY 0.489362 (-5410 2235);
PAINT MONO (-5410 2235);
FORCEPROP 0 LASTPIN (-5400 2275) $PN DG3
J 2
(-5410 2285);
DISPLAY 0.489362 (-5410 2285);
PAINT MONO (-5410 2285);
FORCEPROP 0 LASTPIN (-5400 2025) $PN B3
J 2
(-5410 2035);
DISPLAY 0.489362 (-5410 2035);
PAINT MONO (-5410 2035);
FORCEPROP 0 LASTPIN (-5400 2325) $PN BR53
J 2
(-5410 2335);
DISPLAY 0.489362 (-5410 2335);
PAINT MONO (-5410 2335);
FORCEPROP 0 LASTPIN (-5400 2575) $PN C3
J 2
(-5410 2585);
DISPLAY 0.489362 (-5410 2585);
PAINT MONO (-5410 2585);
FORCEPROP 0 LASTPIN (-5400 2525) $PN BR54
J 2
(-5410 2535);
DISPLAY 0.489362 (-5410 2535);
PAINT MONO (-5410 2535);
FORCEPROP 0 LASTPIN (-5400 2475) $PN DJ3
J 2
(-5410 2485);
DISPLAY 0.489362 (-5410 2485);
PAINT MONO (-5410 2485);
FORCEPROP 0 LASTPIN (-5400 2425) $PN B73
J 2
(-5410 2435);
DISPLAY 0.489362 (-5410 2435);
PAINT MONO (-5410 2435);
FORCEPROP 0 LASTPIN (-3900 4825) $PN C66
J 0
(-3890 4835);
DISPLAY 0.489362 (-3890 4835);
PAINT MONO (-3890 4835);
FORCEPROP 0 LASTPIN (-3900 4775) $PN C65
J 0
(-3890 4785);
DISPLAY 0.489362 (-3890 4785);
PAINT MONO (-3890 4785);
FORCEPROP 0 LASTPIN (-3900 4725) $PN A66
J 0
(-3890 4735);
DISPLAY 0.489362 (-3890 4735);
PAINT MONO (-3890 4735);
FORCEPROP 0 LASTPIN (-3900 4675) $PN A65
J 0
(-3890 4685);
DISPLAY 0.489362 (-3890 4685);
PAINT MONO (-3890 4685);
FORCEPROP 1 LAST MATERIAL IO
J 0
(-5245 6207);
DISPLAY 0.489362 (-5245 6207);
PAINT SKYBLUE (-5245 6207);
FORCEPROP 2 LAST VALUE SOCKET6096_13568-001
J 0
(-5200 6100);
DISPLAY 0.489362 (-5200 6100);
PAINT SKYBLUE (-5200 6100);
FORCEPROP 2 LAST PART_TYPE SMLF
J 0
(-5150 6200);
DISPLAY 1.021277 (-5150 6200);
FORCEPROP 1 LAST PART_NUMBER DGA^6000030
J 0
(-5250 6275);
DISPLAY 0.489362 (-5250 6275);
PAINT SKYBLUE (-5250 6275);
FORCEPROP 2 LAST CDS_LIB pure_quanta
J 0
(-4650 3750);
DISPLAY INVISIBLE (-4650 3750);
FORCEPROP 1 LAST CDS_LMAN_SYM_OUTLINE -600,2425,600,-2425
J 0
(-4650 3750);
DISPLAY 0.468085 (-4650 3750);
PAINT GREEN (-4650 3750);
DISPLAY INVISIBLE (-4650 3750);
FORCEPROP 1 LAST NEEDS_NO_SIZE TRUE
J 0
(-4650 3750);
DISPLAY 0.723404 (-4650 3750);
PAINT GREEN (-4650 3750);
DISPLAY INVISIBLE (-4650 3750);
FORCEPROP 1 LAST PATH I190
J 0
(-4650 3750);
DISPLAY 0.723404 (-4650 3750);
PAINT GREEN (-4650 3750);
DISPLAY INVISIBLE (-4650 3750);
FORCEADD OFFPAGE..4
(-2375 5025);
FORCEPROP 2 LAST $XR1 81 
J 0
(-2099 5025);
DISPLAY 0.638298 (-2099 5025);
PAINT MONO (-2099 5025);
FORCEPROP 2 LAST $XR0 54 
J 0
(-2189 5025);
DISPLAY 0.638298 (-2189 5025);
PAINT MONO (-2189 5025);
FORCEPROP 2 LAST PATH I192
J 0
(-2175 5075);
DISPLAY 1.021277 (-2175 5075);
DISPLAY INVISIBLE (-2175 5075);
FORCEPROP 1 LAST COMMENT_BODY TRUE
J 0
(-2400 4925);
DISPLAY 0.872340 (-2400 4925);
PAINT GREEN (-2400 4925);
DISPLAY INVISIBLE (-2400 4925);
FORCEPROP 1 LAST OFFPAGE TRUE
J 0
(-2050 4900);
DISPLAY 0.872340 (-2050 4900);
PAINT GREEN (-2050 4900);
DISPLAY INVISIBLE (-2050 4900);
FORCEPROP 2 LAST CDS_LIB standard
J 2
(-2375 5025);
DISPLAY INVISIBLE (-2375 5025);
FORCEADD OFFPAGE..3
(-3025 4425);
FORCEPROP 2 LAST $XR0 54 
J 0
(-2811 4425);
DISPLAY 0.638298 (-2811 4425);
PAINT MONO (-2811 4425);
FORCEPROP 2 LAST PATH I198
J 0
(-2800 4475);
DISPLAY 1.021277 (-2800 4475);
DISPLAY INVISIBLE (-2800 4475);
FORCEPROP 1 LAST COMMENT_BODY TRUE
J 0
(-3075 4325);
DISPLAY 0.872340 (-3075 4325);
PAINT GREEN (-3075 4325);
DISPLAY INVISIBLE (-3075 4325);
FORCEPROP 1 LAST OFFPAGE TRUE
J 0
(-2700 4300);
DISPLAY 0.872340 (-2700 4300);
PAINT GREEN (-2700 4300);
DISPLAY INVISIBLE (-2700 4300);
FORCEPROP 2 LAST CDS_LIB standard
J 0
(-3025 4425);
DISPLAY INVISIBLE (-3025 4425);
FORCEADD OFFPAGE..3
(-3025 4475);
FORCEPROP 2 LAST $XR0 54 
J 0
(-2811 4475);
DISPLAY 0.638298 (-2811 4475);
PAINT MONO (-2811 4475);
FORCEPROP 2 LAST PATH I199
J 0
(-2800 4525);
DISPLAY 1.021277 (-2800 4525);
DISPLAY INVISIBLE (-2800 4525);
FORCEPROP 1 LAST COMMENT_BODY TRUE
J 0
(-3075 4375);
DISPLAY 0.872340 (-3075 4375);
PAINT GREEN (-3075 4375);
DISPLAY INVISIBLE (-3075 4375);
FORCEPROP 1 LAST OFFPAGE TRUE
J 0
(-2700 4350);
DISPLAY 0.872340 (-2700 4350);
PAINT GREEN (-2700 4350);
DISPLAY INVISIBLE (-2700 4350);
FORCEPROP 2 LAST CDS_LIB standard
J 0
(-3025 4475);
DISPLAY INVISIBLE (-3025 4475);
FORCEADD OFFPAGE..3
(-3025 4375);
FORCEPROP 2 LAST $XR0 54 
J 0
(-2811 4375);
DISPLAY 0.638298 (-2811 4375);
PAINT MONO (-2811 4375);
FORCEPROP 2 LAST PATH I200
J 0
(-2800 4425);
DISPLAY 1.021277 (-2800 4425);
DISPLAY INVISIBLE (-2800 4425);
FORCEPROP 1 LAST COMMENT_BODY TRUE
J 0
(-3075 4275);
DISPLAY 0.872340 (-3075 4275);
PAINT GREEN (-3075 4275);
DISPLAY INVISIBLE (-3075 4275);
FORCEPROP 1 LAST OFFPAGE TRUE
J 0
(-2700 4250);
DISPLAY 0.872340 (-2700 4250);
PAINT GREEN (-2700 4250);
DISPLAY INVISIBLE (-2700 4250);
FORCEPROP 2 LAST CDS_LIB standard
J 0
(-3025 4375);
DISPLAY INVISIBLE (-3025 4375);
FORCEADD OFFPAGE..3
(-3025 4325);
FORCEPROP 2 LAST $XR0 54 
J 0
(-2811 4325);
DISPLAY 0.638298 (-2811 4325);
PAINT MONO (-2811 4325);
FORCEPROP 2 LAST PATH I201
J 0
(-2800 4375);
DISPLAY 1.021277 (-2800 4375);
DISPLAY INVISIBLE (-2800 4375);
FORCEPROP 1 LAST COMMENT_BODY TRUE
J 0
(-3075 4225);
DISPLAY 0.872340 (-3075 4225);
PAINT GREEN (-3075 4225);
DISPLAY INVISIBLE (-3075 4225);
FORCEPROP 1 LAST OFFPAGE TRUE
J 0
(-2700 4200);
DISPLAY 0.872340 (-2700 4200);
PAINT GREEN (-2700 4200);
DISPLAY INVISIBLE (-2700 4200);
FORCEPROP 2 LAST CDS_LIB standard
J 0
(-3025 4325);
DISPLAY INVISIBLE (-3025 4325);
FORCEADD Q_RES..1
R 2
(-6100 4825);
FORCEPROP 1 LAST LOCATION R529
J 2
(-6200 4825);
DISPLAY 0.489362 (-6200 4825);
PAINT SKYBLUE (-6200 4825);
FORCEPROP 0 LAST $SEC 1
J 0
(-6200 4875);
DISPLAY 0.680851 (-6200 4875);
PAINT MONO (-6200 4875);
DISPLAY INVISIBLE (-6200 4875);
FORCEPROP 0 LAST CDS_SEC 1
J 0
(-6200 4875);
DISPLAY 1.021277 (-6200 4875);
DISPLAY INVISIBLE (-6200 4875);
FORCEPROP 1 LASTPIN (-6000 4825) $PN 1
J 2
(-6012 4837);
DISPLAY 0.489362 (-6012 4837);
PAINT MONO (-6012 4837);
FORCEPROP 1 LASTPIN (-6200 4825) $PN 2
J 2
(-6162 4837);
DISPLAY 0.489362 (-6162 4837);
PAINT MONO (-6162 4837);
FORCEPROP 1 LAST VALUE 0
J 0
(-6000 4825);
DISPLAY 0.489362 (-6000 4825);
PAINT SKYBLUE (-6000 4825);
FORCEPROP 2 LAST CDS_LIB pure_quanta
J 0
(-6100 4825);
DISPLAY INVISIBLE (-6100 4825);
FORCEPROP 1 LAST PATH I203
J 2
(-6050 4975);
DISPLAY 0.978723 (-6050 4975);
PAINT WHITE (-6050 4975);
DISPLAY INVISIBLE (-6050 4975);
FORCEPROP 1 LAST WATTAGE 1/16W
J 0
(-6500 4750);
DISPLAY 0.489362 (-6500 4750);
PAINT SKYBLUE (-6500 4750);
DISPLAY INVISIBLE (-6500 4750);
FORCEPROP 1 LAST MATERIAL CHIP
J 2
(-6525 4750);
DISPLAY 0.489362 (-6525 4750);
PAINT SKYBLUE (-6525 4750);
DISPLAY INVISIBLE (-6525 4750);
FORCEPROP 1 LAST TOLERANCE 5%
J 2
(-6075 4750);
DISPLAY 0.489362 (-6075 4750);
PAINT SKYBLUE (-6075 4750);
DISPLAY INVISIBLE (-6075 4750);
FORCEPROP 1 LAST PART_NUMBER CS00002JB38
J 2
(-6125 4875);
DISPLAY 0.489362 (-6125 4875);
PAINT SKYBLUE (-6125 4875);
DISPLAY INVISIBLE (-6125 4875);
FORCEPROP 1 LAST PACK_TYPE 0402LF
J 2
(-6150 4750);
DISPLAY 0.489362 (-6150 4750);
PAINT SKYBLUE (-6150 4750);
DISPLAY INVISIBLE (-6150 4750);
FORCEADD OFFPAGE..4
R 2
(-6200 5925);
FORCEPROP 2 LAST $XR1 82 
J 0
(-6511 5925);
DISPLAY 0.638298 (-6511 5925);
PAINT MONO (-6511 5925);
FORCEPROP 2 LAST $XR0 80 
J 0
(-6421 5925);
DISPLAY 0.638298 (-6421 5925);
PAINT MONO (-6421 5925);
FORCEPROP 2 LAST PATH I204
J 0
(-6925 5975);
DISPLAY 1.021277 (-6925 5975);
DISPLAY INVISIBLE (-6925 5975);
FORCEPROP 1 LAST COMMENT_BODY TRUE
J 2
(-6175 5825);
DISPLAY 0.872340 (-6175 5825);
PAINT GREEN (-6175 5825);
DISPLAY INVISIBLE (-6175 5825);
FORCEPROP 1 LAST OFFPAGE TRUE
J 2
(-6525 5800);
DISPLAY 0.872340 (-6525 5800);
PAINT GREEN (-6525 5800);
DISPLAY INVISIBLE (-6525 5800);
FORCEPROP 2 LAST CDS_LIB standard
J 0
(-6200 5925);
DISPLAY INVISIBLE (-6200 5925);
FORCEADD OFFPAGE..4
R 2
(-6200 5875);
FORCEPROP 2 LAST $XR1 82 
J 0
(-6511 5875);
DISPLAY 0.638298 (-6511 5875);
PAINT MONO (-6511 5875);
FORCEPROP 2 LAST $XR0 80 
J 0
(-6421 5875);
DISPLAY 0.638298 (-6421 5875);
PAINT MONO (-6421 5875);
FORCEPROP 2 LAST PATH I205
J 0
(-6450 5925);
DISPLAY 1.021277 (-6450 5925);
DISPLAY INVISIBLE (-6450 5925);
FORCEPROP 1 LAST COMMENT_BODY TRUE
J 2
(-6175 5775);
DISPLAY 0.872340 (-6175 5775);
PAINT GREEN (-6175 5775);
DISPLAY INVISIBLE (-6175 5775);
FORCEPROP 1 LAST OFFPAGE TRUE
J 2
(-6525 5750);
DISPLAY 0.872340 (-6525 5750);
PAINT GREEN (-6525 5750);
DISPLAY INVISIBLE (-6525 5750);
FORCEPROP 2 LAST CDS_LIB standard
J 0
(-6200 5875);
DISPLAY INVISIBLE (-6200 5875);
FORCEADD OFFPAGE..4
R 2
(-6200 5675);
FORCEPROP 2 LAST $XR0 186 
J 0
(-6452 5675);
DISPLAY 0.638298 (-6452 5675);
PAINT MONO (-6452 5675);
FORCEPROP 2 LAST PATH I208
J 0
(-6450 5725);
DISPLAY 1.021277 (-6450 5725);
DISPLAY INVISIBLE (-6450 5725);
FORCEPROP 1 LAST COMMENT_BODY TRUE
J 2
(-6175 5575);
DISPLAY 0.872340 (-6175 5575);
PAINT GREEN (-6175 5575);
DISPLAY INVISIBLE (-6175 5575);
FORCEPROP 1 LAST OFFPAGE TRUE
J 2
(-6525 5550);
DISPLAY 0.872340 (-6525 5550);
PAINT GREEN (-6525 5550);
DISPLAY INVISIBLE (-6525 5550);
FORCEPROP 2 LAST CDS_LIB standard
J 0
(-6200 5675);
DISPLAY INVISIBLE (-6200 5675);
FORCEADD OFFPAGE..4
R 2
(-6200 5475);
FORCEPROP 2 LAST $XR0 193 
J 0
(-6452 5475);
DISPLAY 0.638298 (-6452 5475);
PAINT MONO (-6452 5475);
FORCEPROP 2 LAST PATH I211
J 0
(-6450 5525);
DISPLAY 1.021277 (-6450 5525);
DISPLAY INVISIBLE (-6450 5525);
FORCEPROP 1 LAST COMMENT_BODY TRUE
J 2
(-6175 5375);
DISPLAY 0.872340 (-6175 5375);
PAINT GREEN (-6175 5375);
DISPLAY INVISIBLE (-6175 5375);
FORCEPROP 1 LAST OFFPAGE TRUE
J 2
(-6525 5350);
DISPLAY 0.872340 (-6525 5350);
PAINT GREEN (-6525 5350);
DISPLAY INVISIBLE (-6525 5350);
FORCEPROP 2 LAST CDS_LIB standard
J 0
(-6200 5475);
DISPLAY INVISIBLE (-6200 5475);
FORCEADD OFFPAGE..4
R 2
(-6100 5125);
FORCEPROP 2 LAST $XR0 138 
J 0
(-6352 5125);
DISPLAY 0.638298 (-6352 5125);
PAINT MONO (-6352 5125);
FORCEPROP 2 LAST PATH I216
J 0
(-6375 5175);
DISPLAY 1.021277 (-6375 5175);
DISPLAY INVISIBLE (-6375 5175);
FORCEPROP 1 LAST COMMENT_BODY TRUE
J 2
(-6075 5025);
DISPLAY 0.872340 (-6075 5025);
PAINT GREEN (-6075 5025);
DISPLAY INVISIBLE (-6075 5025);
FORCEPROP 1 LAST OFFPAGE TRUE
J 2
(-6425 5000);
DISPLAY 0.872340 (-6425 5000);
PAINT GREEN (-6425 5000);
DISPLAY INVISIBLE (-6425 5000);
FORCEPROP 2 LAST CDS_LIB standard
J 0
(-6100 5125);
DISPLAY INVISIBLE (-6100 5125);
FORCEADD OFFPAGE..4
R 2
(-6100 5075);
FORCEPROP 2 LAST $XR0 138 
J 0
(-6352 5075);
DISPLAY 0.638298 (-6352 5075);
PAINT MONO (-6352 5075);
FORCEPROP 2 LAST PATH I217
J 0
(-6375 5125);
DISPLAY 1.021277 (-6375 5125);
DISPLAY INVISIBLE (-6375 5125);
FORCEPROP 1 LAST COMMENT_BODY TRUE
J 2
(-6075 4975);
DISPLAY 0.872340 (-6075 4975);
PAINT GREEN (-6075 4975);
DISPLAY INVISIBLE (-6075 4975);
FORCEPROP 1 LAST OFFPAGE TRUE
J 2
(-6425 4950);
DISPLAY 0.872340 (-6425 4950);
PAINT GREEN (-6425 4950);
DISPLAY INVISIBLE (-6425 4950);
FORCEPROP 2 LAST CDS_LIB standard
J 0
(-6100 5075);
DISPLAY INVISIBLE (-6100 5075);
FORCEADD OFFPAGE..4
R 2
(-6850 4775);
FORCEPROP 2 LAST $XR1 151 
J 0
(-7221 4775);
DISPLAY 0.638298 (-7221 4775);
PAINT MONO (-7221 4775);
FORCEPROP 2 LAST $XR0 54 
J 0
(-7101 4775);
DISPLAY 0.638298 (-7101 4775);
PAINT MONO (-7101 4775);
FORCEPROP 2 LAST PATH I219
J 0
(-7050 4825);
DISPLAY 1.021277 (-7050 4825);
DISPLAY INVISIBLE (-7050 4825);
FORCEPROP 1 LAST COMMENT_BODY TRUE
J 2
(-6825 4675);
DISPLAY 0.872340 (-6825 4675);
PAINT GREEN (-6825 4675);
DISPLAY INVISIBLE (-6825 4675);
FORCEPROP 1 LAST OFFPAGE TRUE
J 2
(-7175 4650);
DISPLAY 0.872340 (-7175 4650);
PAINT GREEN (-7175 4650);
DISPLAY INVISIBLE (-7175 4650);
FORCEPROP 2 LAST CDS_LIB standard
J 0
(-6850 4775);
DISPLAY INVISIBLE (-6850 4775);
FORCEADD OFFPAGE..2
R 2
(-6850 4825);
FORCEPROP 2 LAST $XR1 151 
J 0
(-7224 4825);
DISPLAY 0.638298 (-7224 4825);
PAINT MONO (-7224 4825);
FORCEPROP 2 LAST $XR0 54 
J 0
(-7104 4825);
DISPLAY 0.638298 (-7104 4825);
PAINT MONO (-7104 4825);
FORCEPROP 2 LAST PATH I220
J 0
(-7050 4875);
DISPLAY 1.021277 (-7050 4875);
DISPLAY INVISIBLE (-7050 4875);
FORCEPROP 1 LAST COMMENT_BODY TRUE
J 2
(-6805 4730);
DISPLAY 0.872340 (-6805 4730);
PAINT GREEN (-6805 4730);
DISPLAY INVISIBLE (-6805 4730);
FORCEPROP 1 LAST OFFPAGE TRUE
J 2
(-7175 4700);
DISPLAY 0.872340 (-7175 4700);
PAINT GREEN (-7175 4700);
DISPLAY INVISIBLE (-7175 4700);
FORCEPROP 2 LAST CDS_LIB standard
J 2
(-6850 4825);
DISPLAY INVISIBLE (-6850 4825);
FORCEADD OFFPAGE..4
R 2
(-6850 4725);
FORCEPROP 2 LAST $XR1 150 
J 0
(-7191 4725);
DISPLAY 0.638298 (-7191 4725);
PAINT MONO (-7191 4725);
FORCEPROP 2 LAST $XR0 54 
J 0
(-7071 4725);
DISPLAY 0.638298 (-7071 4725);
PAINT MONO (-7071 4725);
FORCEPROP 2 LAST PATH I221
J 0
(-7050 4775);
DISPLAY 1.021277 (-7050 4775);
DISPLAY INVISIBLE (-7050 4775);
FORCEPROP 1 LAST COMMENT_BODY TRUE
J 2
(-6825 4625);
DISPLAY 0.872340 (-6825 4625);
PAINT GREEN (-6825 4625);
DISPLAY INVISIBLE (-6825 4625);
FORCEPROP 1 LAST OFFPAGE TRUE
J 2
(-7175 4600);
DISPLAY 0.872340 (-7175 4600);
PAINT GREEN (-7175 4600);
DISPLAY INVISIBLE (-7175 4600);
FORCEPROP 2 LAST CDS_LIB standard
J 2
(-6850 4725);
DISPLAY INVISIBLE (-6850 4725);
FORCEADD OFFPAGE..4
R 2
(-6850 4675);
FORCEPROP 2 LAST $XR1 150 
J 0
(-7191 4675);
DISPLAY 0.638298 (-7191 4675);
PAINT MONO (-7191 4675);
FORCEPROP 2 LAST $XR0 54 
J 0
(-7071 4675);
DISPLAY 0.638298 (-7071 4675);
PAINT MONO (-7071 4675);
FORCEPROP 2 LAST PATH I222
J 0
(-7050 4725);
DISPLAY 1.021277 (-7050 4725);
DISPLAY INVISIBLE (-7050 4725);
FORCEPROP 1 LAST COMMENT_BODY TRUE
J 2
(-6825 4575);
DISPLAY 0.872340 (-6825 4575);
PAINT GREEN (-6825 4575);
DISPLAY INVISIBLE (-6825 4575);
FORCEPROP 1 LAST OFFPAGE TRUE
J 2
(-7175 4550);
DISPLAY 0.872340 (-7175 4550);
PAINT GREEN (-7175 4550);
DISPLAY INVISIBLE (-7175 4550);
FORCEPROP 2 LAST CDS_LIB standard
J 0
(-6850 4675);
DISPLAY INVISIBLE (-6850 4675);
FORCEADD OFFPAGE..4
R 2
(-6850 4625);
FORCEPROP 2 LAST $XR1 150 
J 0
(-7191 4625);
DISPLAY 0.638298 (-7191 4625);
PAINT MONO (-7191 4625);
FORCEPROP 2 LAST $XR0 54 
J 0
(-7071 4625);
DISPLAY 0.638298 (-7071 4625);
PAINT MONO (-7071 4625);
FORCEPROP 2 LAST PATH I224
J 0
(-7050 4675);
DISPLAY 1.021277 (-7050 4675);
DISPLAY INVISIBLE (-7050 4675);
FORCEPROP 1 LAST COMMENT_BODY TRUE
J 2
(-6825 4525);
DISPLAY 0.872340 (-6825 4525);
PAINT GREEN (-6825 4525);
DISPLAY INVISIBLE (-6825 4525);
FORCEPROP 1 LAST OFFPAGE TRUE
J 2
(-7175 4500);
DISPLAY 0.872340 (-7175 4500);
PAINT GREEN (-7175 4500);
DISPLAY INVISIBLE (-7175 4500);
FORCEPROP 2 LAST CDS_LIB standard
J 0
(-6850 4625);
DISPLAY INVISIBLE (-6850 4625);
FORCEADD OFFPAGE..4
R 2
(-6850 4525);
FORCEPROP 2 LAST $XR1 150 
J 0
(-7191 4525);
DISPLAY 0.638298 (-7191 4525);
PAINT MONO (-7191 4525);
FORCEPROP 2 LAST $XR0 54 
J 0
(-7071 4525);
DISPLAY 0.638298 (-7071 4525);
PAINT MONO (-7071 4525);
FORCEPROP 2 LAST PATH I225
J 0
(-7050 4575);
DISPLAY 1.021277 (-7050 4575);
DISPLAY INVISIBLE (-7050 4575);
FORCEPROP 1 LAST COMMENT_BODY TRUE
J 2
(-6825 4425);
DISPLAY 0.872340 (-6825 4425);
PAINT GREEN (-6825 4425);
DISPLAY INVISIBLE (-6825 4425);
FORCEPROP 1 LAST OFFPAGE TRUE
J 2
(-7175 4400);
DISPLAY 0.872340 (-7175 4400);
PAINT GREEN (-7175 4400);
DISPLAY INVISIBLE (-7175 4400);
FORCEPROP 2 LAST CDS_LIB standard
J 0
(-6850 4525);
DISPLAY INVISIBLE (-6850 4525);
FORCEADD OFFPAGE..2
(-7900 4650);
FORCEPROP 2 LAST $XR1 54 
J 0
(-7621 4650);
DISPLAY 0.638298 (-7621 4650);
PAINT MONO (-7621 4650);
FORCEPROP 2 LAST $XR0 81 
J 0
(-7711 4650);
DISPLAY 0.638298 (-7711 4650);
PAINT MONO (-7711 4650);
FORCEPROP 2 LAST PATH I235
J 0
(-7575 4700);
DISPLAY 1.021277 (-7575 4700);
DISPLAY INVISIBLE (-7575 4700);
FORCEPROP 1 LAST COMMENT_BODY TRUE
J 0
(-7945 4555);
DISPLAY 0.872340 (-7945 4555);
PAINT PEACH (-7945 4555);
DISPLAY INVISIBLE (-7945 4555);
FORCEPROP 1 LAST OFFPAGE TRUE
J 0
(-7575 4525);
DISPLAY 0.872340 (-7575 4525);
PAINT GREEN (-7575 4525);
DISPLAY INVISIBLE (-7575 4525);
FORCEPROP 2 LAST CDS_LIB standard
J 0
(-7900 4650);
DISPLAY INVISIBLE (-7900 4650);
FORCEADD OFFPAGE..2
(-7900 4600);
FORCEPROP 2 LAST $XR1 54 
J 0
(-7621 4600);
DISPLAY 0.638298 (-7621 4600);
PAINT MONO (-7621 4600);
FORCEPROP 2 LAST $XR0 81 
J 0
(-7711 4600);
DISPLAY 0.638298 (-7711 4600);
PAINT MONO (-7711 4600);
FORCEPROP 2 LAST PATH I236
J 0
(-7575 4650);
DISPLAY 1.021277 (-7575 4650);
DISPLAY INVISIBLE (-7575 4650);
FORCEPROP 1 LAST COMMENT_BODY TRUE
J 0
(-7945 4505);
DISPLAY 0.872340 (-7945 4505);
PAINT PEACH (-7945 4505);
DISPLAY INVISIBLE (-7945 4505);
FORCEPROP 1 LAST OFFPAGE TRUE
J 0
(-7575 4475);
DISPLAY 0.872340 (-7575 4475);
PAINT GREEN (-7575 4475);
DISPLAY INVISIBLE (-7575 4475);
FORCEPROP 2 LAST CDS_LIB standard
J 0
(-7900 4600);
DISPLAY INVISIBLE (-7900 4600);
FORCEADD TP..1
R 6
(-6150 1900);
FORCEPROP 1 LAST LOCATION TP20
J 1
(-6150 1802);
DISPLAY 0.489362 (-6150 1802);
PAINT SKYBLUE (-6150 1802);
FORCEPROP 0 LAST $SEC 1
J 0
(-6175 1875);
DISPLAY 0.680851 (-6175 1875);
PAINT MONO (-6175 1875);
DISPLAY INVISIBLE (-6175 1875);
FORCEPROP 0 LAST CDS_SEC 1
J 0
(-6175 1875);
DISPLAY 1.021277 (-6175 1875);
DISPLAY INVISIBLE (-6175 1875);
FORCEPROP 0 LASTPIN (-6150 1950) $PN 1
R 1
J 0
(-6160 1960);
DISPLAY 0.489362 (-6160 1960);
PAINT MONO (-6160 1960);
FORCEPROP 1 LAST MATERIAL NA
J 0
(-6175 1852);
DISPLAY 0.489362 (-6175 1852);
PAINT SKYBLUE (-6175 1852);
FORCEPROP 1 LASTPIN (-6150 1950) $PIN_NUMBER ?
J 2
(-6100 1917);
DISPLAY 0.702128 (-6100 1917);
PAINT MONO (-6100 1917);
DISPLAY INVISIBLE (-6100 1917);
FORCEPROP 2 LAST CDS_LIB pure_quanta
R 3
J 2
(-6150 1853);
DISPLAY INVISIBLE (-6150 1853);
FORCEPROP 1 LAST PATH I237
J 1
(-6145 1855);
DISPLAY 0.446809 (-6145 1855);
PAINT GREEN (-6145 1855);
DISPLAY INVISIBLE (-6145 1855);
FORCEPROP 1 LAST PART_NUMBER TP30
J 1
(-6095 1924);
DISPLAY 0.446809 (-6095 1924);
PAINT SKYBLUE (-6095 1924);
DISPLAY INVISIBLE (-6095 1924);
FORCEPROP 1 LAST PACK_TYPE TP
J 1
(-6095 1944);
DISPLAY 0.446809 (-6095 1944);
PAINT SKYBLUE (-6095 1944);
DISPLAY INVISIBLE (-6095 1944);
FORCEADD TP..1
R 6
(-6225 1900);
FORCEPROP 1 LAST LOCATION TP19
J 1
(-6225 1802);
DISPLAY 0.489362 (-6225 1802);
PAINT SKYBLUE (-6225 1802);
FORCEPROP 0 LAST $SEC 1
J 0
(-6250 1875);
DISPLAY 0.680851 (-6250 1875);
PAINT MONO (-6250 1875);
DISPLAY INVISIBLE (-6250 1875);
FORCEPROP 0 LAST CDS_SEC 1
J 0
(-6250 1875);
DISPLAY 1.021277 (-6250 1875);
DISPLAY INVISIBLE (-6250 1875);
FORCEPROP 0 LASTPIN (-6225 1950) $PN 1
R 1
J 0
(-6235 1960);
DISPLAY 0.489362 (-6235 1960);
PAINT MONO (-6235 1960);
FORCEPROP 1 LAST MATERIAL NA
J 0
(-6250 1852);
DISPLAY 0.489362 (-6250 1852);
PAINT SKYBLUE (-6250 1852);
FORCEPROP 1 LASTPIN (-6225 1950) $PIN_NUMBER ?
J 2
(-6175 1950);
DISPLAY 0.702128 (-6175 1950);
PAINT MONO (-6175 1950);
DISPLAY INVISIBLE (-6175 1950);
FORCEPROP 2 LAST CDS_LIB pure_quanta
J 0
(-6225 1900);
DISPLAY INVISIBLE (-6225 1900);
FORCEPROP 1 LAST PATH I238
J 1
(-6220 1855);
DISPLAY 0.446809 (-6220 1855);
PAINT GREEN (-6220 1855);
DISPLAY INVISIBLE (-6220 1855);
FORCEPROP 1 LAST PART_NUMBER TP30
J 1
(-6170 1924);
DISPLAY 0.446809 (-6170 1924);
PAINT SKYBLUE (-6170 1924);
DISPLAY INVISIBLE (-6170 1924);
FORCEPROP 1 LAST PACK_TYPE TP
J 1
(-6170 1944);
DISPLAY 0.446809 (-6170 1944);
PAINT SKYBLUE (-6170 1944);
DISPLAY INVISIBLE (-6170 1944);
FORCEADD UNIVERSAL_GND..1
(-5650 1225);
FORCEPROP 3 LASTPIN (-5650 1275) SIG_NAME GND\g
J 0
(-5640 1285);
DISPLAY 0.659574 (-5640 1285);
PAINT MONO (-5640 1285);
DISPLAY INVISIBLE (-5640 1285);
FORCEPROP 2 LAST CDS_LIB pure_quanta_power
J 0
(-5650 1225);
DISPLAY INVISIBLE (-5650 1225);
FORCEPROP 1 LAST PATH I239
J 0
(-5575 1225);
DISPLAY 0.872340 (-5575 1225);
PAINT AQUA (-5575 1225);
DISPLAY INVISIBLE (-5575 1225);
FORCEPROP 1 LAST HDL_POWER GND
J 1
(-5625 1150);
DISPLAY 0.872340 (-5625 1150);
PAINT GREEN (-5625 1150);
DISPLAY INVISIBLE (-5625 1150);
FORCEADD TP..1
R 6
(-6325 1900);
FORCEPROP 1 LAST LOCATION TP18
J 1
(-6325 1802);
DISPLAY 0.489362 (-6325 1802);
PAINT SKYBLUE (-6325 1802);
FORCEPROP 0 LAST $SEC 1
J 0
(-6350 1875);
DISPLAY 0.680851 (-6350 1875);
PAINT MONO (-6350 1875);
DISPLAY INVISIBLE (-6350 1875);
FORCEPROP 0 LAST CDS_SEC 1
J 0
(-6350 1875);
DISPLAY 1.021277 (-6350 1875);
DISPLAY INVISIBLE (-6350 1875);
FORCEPROP 0 LASTPIN (-6325 1950) $PN 1
R 1
J 0
(-6335 1960);
DISPLAY 0.489362 (-6335 1960);
PAINT MONO (-6335 1960);
FORCEPROP 1 LAST MATERIAL NA
J 0
(-6350 1852);
DISPLAY 0.489362 (-6350 1852);
PAINT SKYBLUE (-6350 1852);
FORCEPROP 2 LAST CDS_LIB pure_quanta
J 0
(-6325 1900);
DISPLAY INVISIBLE (-6325 1900);
FORCEPROP 1 LASTPIN (-6325 1950) $PIN_NUMBER ?
J 2
(-6275 1950);
DISPLAY 0.702128 (-6275 1950);
PAINT MONO (-6275 1950);
DISPLAY INVISIBLE (-6275 1950);
FORCEPROP 1 LAST PATH I240
J 1
(-6320 1855);
DISPLAY 0.446809 (-6320 1855);
PAINT GREEN (-6320 1855);
DISPLAY INVISIBLE (-6320 1855);
FORCEPROP 1 LAST PART_NUMBER TP30
J 1
(-6270 1924);
DISPLAY 0.446809 (-6270 1924);
PAINT SKYBLUE (-6270 1924);
DISPLAY INVISIBLE (-6270 1924);
FORCEPROP 1 LAST PACK_TYPE TP
J 1
(-6270 1944);
DISPLAY 0.446809 (-6270 1944);
PAINT SKYBLUE (-6270 1944);
DISPLAY INVISIBLE (-6270 1944);
FORCEADD TP..1
R 6
(-6400 1900);
FORCEPROP 1 LAST LOCATION TP17
J 1
(-6400 1802);
DISPLAY 0.489362 (-6400 1802);
PAINT SKYBLUE (-6400 1802);
FORCEPROP 0 LAST $SEC 1
J 0
(-6425 1875);
DISPLAY 0.680851 (-6425 1875);
PAINT MONO (-6425 1875);
DISPLAY INVISIBLE (-6425 1875);
FORCEPROP 0 LAST CDS_SEC 1
J 0
(-6425 1875);
DISPLAY 1.021277 (-6425 1875);
DISPLAY INVISIBLE (-6425 1875);
FORCEPROP 0 LASTPIN (-6400 1950) $PN 1
R 1
J 0
(-6410 1960);
DISPLAY 0.489362 (-6410 1960);
PAINT MONO (-6410 1960);
FORCEPROP 1 LAST MATERIAL NA
J 0
(-6425 1852);
DISPLAY 0.489362 (-6425 1852);
PAINT SKYBLUE (-6425 1852);
FORCEPROP 2 LAST CDS_LIB pure_quanta
J 0
(-6400 1900);
DISPLAY INVISIBLE (-6400 1900);
FORCEPROP 1 LASTPIN (-6400 1950) $PIN_NUMBER ?
J 2
(-6350 1950);
DISPLAY 0.702128 (-6350 1950);
PAINT MONO (-6350 1950);
DISPLAY INVISIBLE (-6350 1950);
FORCEPROP 1 LAST PATH I241
J 1
(-6395 1855);
DISPLAY 0.446809 (-6395 1855);
PAINT GREEN (-6395 1855);
DISPLAY INVISIBLE (-6395 1855);
FORCEPROP 1 LAST PART_NUMBER TP30
J 1
(-6345 1924);
DISPLAY 0.446809 (-6345 1924);
PAINT SKYBLUE (-6345 1924);
DISPLAY INVISIBLE (-6345 1924);
FORCEPROP 1 LAST PACK_TYPE TP
J 1
(-6345 1944);
DISPLAY 0.446809 (-6345 1944);
PAINT SKYBLUE (-6345 1944);
DISPLAY INVISIBLE (-6345 1944);
FORCEADD TP..1
R 6
(-6475 1900);
FORCEPROP 1 LAST LOCATION TP16
J 1
(-6475 1802);
DISPLAY 0.489362 (-6475 1802);
PAINT SKYBLUE (-6475 1802);
FORCEPROP 0 LAST $SEC 1
J 0
(-6500 1875);
DISPLAY 0.680851 (-6500 1875);
PAINT MONO (-6500 1875);
DISPLAY INVISIBLE (-6500 1875);
FORCEPROP 0 LAST CDS_SEC 1
J 0
(-6500 1875);
DISPLAY 1.021277 (-6500 1875);
DISPLAY INVISIBLE (-6500 1875);
FORCEPROP 0 LASTPIN (-6475 1950) $PN 1
R 1
J 0
(-6485 1960);
DISPLAY 0.489362 (-6485 1960);
PAINT MONO (-6485 1960);
FORCEPROP 1 LAST MATERIAL NA
J 0
(-6500 1852);
DISPLAY 0.489362 (-6500 1852);
PAINT SKYBLUE (-6500 1852);
FORCEPROP 1 LASTPIN (-6475 1950) $PIN_NUMBER ?
J 2
(-6425 1950);
DISPLAY 0.702128 (-6425 1950);
PAINT MONO (-6425 1950);
DISPLAY INVISIBLE (-6425 1950);
FORCEPROP 2 LAST CDS_LIB pure_quanta
J 0
(-6475 1900);
DISPLAY INVISIBLE (-6475 1900);
FORCEPROP 1 LAST PATH I242
J 1
(-6470 1855);
DISPLAY 0.446809 (-6470 1855);
PAINT GREEN (-6470 1855);
DISPLAY INVISIBLE (-6470 1855);
FORCEPROP 1 LAST PART_NUMBER TP30
J 1
(-6420 1924);
DISPLAY 0.446809 (-6420 1924);
PAINT SKYBLUE (-6420 1924);
DISPLAY INVISIBLE (-6420 1924);
FORCEPROP 1 LAST PACK_TYPE TP
J 1
(-6420 1944);
DISPLAY 0.446809 (-6420 1944);
PAINT SKYBLUE (-6420 1944);
DISPLAY INVISIBLE (-6420 1944);
FORCEADD TP..1
R 6
(-6550 1900);
FORCEPROP 1 LAST LOCATION TP15
J 1
(-6550 1802);
DISPLAY 0.489362 (-6550 1802);
PAINT SKYBLUE (-6550 1802);
FORCEPROP 0 LAST $SEC 1
J 0
(-6575 1875);
DISPLAY 0.680851 (-6575 1875);
PAINT MONO (-6575 1875);
DISPLAY INVISIBLE (-6575 1875);
FORCEPROP 0 LAST CDS_SEC 1
J 0
(-6575 1875);
DISPLAY 1.021277 (-6575 1875);
DISPLAY INVISIBLE (-6575 1875);
FORCEPROP 0 LASTPIN (-6550 1950) $PN 1
R 1
J 0
(-6560 1960);
DISPLAY 0.489362 (-6560 1960);
PAINT MONO (-6560 1960);
FORCEPROP 1 LAST MATERIAL NA
J 0
(-6575 1852);
DISPLAY 0.489362 (-6575 1852);
PAINT SKYBLUE (-6575 1852);
FORCEPROP 1 LASTPIN (-6550 1950) $PIN_NUMBER ?
J 2
(-6500 1950);
DISPLAY 0.702128 (-6500 1950);
PAINT MONO (-6500 1950);
DISPLAY INVISIBLE (-6500 1950);
FORCEPROP 2 LAST CDS_LIB pure_quanta
J 0
(-6550 1900);
DISPLAY INVISIBLE (-6550 1900);
FORCEPROP 1 LAST PATH I243
J 1
(-6545 1855);
DISPLAY 0.446809 (-6545 1855);
PAINT GREEN (-6545 1855);
DISPLAY INVISIBLE (-6545 1855);
FORCEPROP 1 LAST PART_NUMBER TP30
J 1
(-6495 1924);
DISPLAY 0.446809 (-6495 1924);
PAINT SKYBLUE (-6495 1924);
DISPLAY INVISIBLE (-6495 1924);
FORCEPROP 1 LAST PACK_TYPE TP
J 1
(-6495 1944);
DISPLAY 0.446809 (-6495 1944);
PAINT SKYBLUE (-6495 1944);
DISPLAY INVISIBLE (-6495 1944);
FORCEADD TP..1
R 6
(-6675 1900);
FORCEPROP 1 LAST LOCATION TP14
J 1
(-6675 1802);
DISPLAY 0.489362 (-6675 1802);
PAINT SKYBLUE (-6675 1802);
FORCEPROP 0 LAST $SEC 1
J 0
(-6700 1875);
DISPLAY 0.680851 (-6700 1875);
PAINT MONO (-6700 1875);
DISPLAY INVISIBLE (-6700 1875);
FORCEPROP 0 LAST CDS_SEC 1
J 0
(-6700 1875);
DISPLAY 1.021277 (-6700 1875);
DISPLAY INVISIBLE (-6700 1875);
FORCEPROP 0 LASTPIN (-6675 1950) $PN 1
R 1
J 0
(-6685 1960);
DISPLAY 0.489362 (-6685 1960);
PAINT MONO (-6685 1960);
FORCEPROP 1 LAST MATERIAL NA
J 0
(-6700 1852);
DISPLAY 0.489362 (-6700 1852);
PAINT SKYBLUE (-6700 1852);
FORCEPROP 2 LAST CDS_LIB pure_quanta
J 0
(-6675 1900);
DISPLAY INVISIBLE (-6675 1900);
FORCEPROP 1 LASTPIN (-6675 1950) $PIN_NUMBER ?
J 2
(-6625 1950);
DISPLAY 0.702128 (-6625 1950);
PAINT MONO (-6625 1950);
DISPLAY INVISIBLE (-6625 1950);
FORCEPROP 1 LAST PATH I244
J 1
(-6670 1855);
DISPLAY 0.446809 (-6670 1855);
PAINT GREEN (-6670 1855);
DISPLAY INVISIBLE (-6670 1855);
FORCEPROP 1 LAST PART_NUMBER TP30
J 1
(-6620 1924);
DISPLAY 0.446809 (-6620 1924);
PAINT SKYBLUE (-6620 1924);
DISPLAY INVISIBLE (-6620 1924);
FORCEPROP 1 LAST PACK_TYPE TP
J 1
(-6620 1944);
DISPLAY 0.446809 (-6620 1944);
PAINT SKYBLUE (-6620 1944);
DISPLAY INVISIBLE (-6620 1944);
FORCEADD TP..1
R 6
(-6750 1900);
FORCEPROP 1 LAST LOCATION TP13
J 1
(-6750 1802);
DISPLAY 0.489362 (-6750 1802);
PAINT SKYBLUE (-6750 1802);
FORCEPROP 0 LAST $SEC 1
J 0
(-6775 1875);
DISPLAY 0.680851 (-6775 1875);
PAINT MONO (-6775 1875);
DISPLAY INVISIBLE (-6775 1875);
FORCEPROP 0 LAST CDS_SEC 1
J 0
(-6775 1875);
DISPLAY 1.021277 (-6775 1875);
DISPLAY INVISIBLE (-6775 1875);
FORCEPROP 0 LASTPIN (-6750 1950) $PN 1
R 1
J 0
(-6760 1960);
DISPLAY 0.489362 (-6760 1960);
PAINT MONO (-6760 1960);
FORCEPROP 1 LAST MATERIAL NA
J 0
(-6775 1852);
DISPLAY 0.489362 (-6775 1852);
PAINT SKYBLUE (-6775 1852);
FORCEPROP 2 LAST CDS_LIB pure_quanta
J 0
(-6750 1900);
DISPLAY INVISIBLE (-6750 1900);
FORCEPROP 1 LASTPIN (-6750 1950) $PIN_NUMBER ?
J 2
(-6700 1950);
DISPLAY 0.702128 (-6700 1950);
PAINT MONO (-6700 1950);
DISPLAY INVISIBLE (-6700 1950);
FORCEPROP 1 LAST PATH I245
J 1
(-6745 1855);
DISPLAY 0.446809 (-6745 1855);
PAINT GREEN (-6745 1855);
DISPLAY INVISIBLE (-6745 1855);
FORCEPROP 1 LAST PART_NUMBER TP30
J 1
(-6695 1924);
DISPLAY 0.446809 (-6695 1924);
PAINT SKYBLUE (-6695 1924);
DISPLAY INVISIBLE (-6695 1924);
FORCEPROP 1 LAST PACK_TYPE TP
J 1
(-6695 1944);
DISPLAY 0.446809 (-6695 1944);
PAINT SKYBLUE (-6695 1944);
DISPLAY INVISIBLE (-6695 1944);
FORCEADD OFFPAGE..2
R 2
(-6650 3325);
FORCEPROP 2 LAST $XR0 144 
J 0
(-6905 3325);
DISPLAY 0.638298 (-6905 3325);
PAINT MONO (-6905 3325);
FORCEPROP 2 LAST PATH I246
J 0
(-6850 3375);
DISPLAY 1.021277 (-6850 3375);
DISPLAY INVISIBLE (-6850 3375);
FORCEPROP 1 LAST COMMENT_BODY TRUE
J 2
(-6605 3230);
DISPLAY 0.872340 (-6605 3230);
PAINT GREEN (-6605 3230);
DISPLAY INVISIBLE (-6605 3230);
FORCEPROP 1 LAST OFFPAGE TRUE
J 2
(-6975 3200);
DISPLAY 0.872340 (-6975 3200);
PAINT GREEN (-6975 3200);
DISPLAY INVISIBLE (-6975 3200);
FORCEPROP 2 LAST CDS_LIB standard
J 0
(-6650 3325);
DISPLAY INVISIBLE (-6650 3325);
FORCEADD OFFPAGE..4
R 2
(-6650 3225);
FORCEPROP 2 LAST $XR1 81 
J 0
(-6961 3225);
DISPLAY 0.638298 (-6961 3225);
PAINT MONO (-6961 3225);
FORCEPROP 2 LAST $XR0 54 
J 0
(-6871 3225);
DISPLAY 0.638298 (-6871 3225);
PAINT MONO (-6871 3225);
FORCEPROP 2 LAST PATH I247
J 0
(-6900 3275);
DISPLAY 1.021277 (-6900 3275);
DISPLAY INVISIBLE (-6900 3275);
FORCEPROP 1 LAST COMMENT_BODY TRUE
J 2
(-6625 3125);
DISPLAY 0.872340 (-6625 3125);
PAINT GREEN (-6625 3125);
DISPLAY INVISIBLE (-6625 3125);
FORCEPROP 1 LAST OFFPAGE TRUE
J 2
(-6975 3100);
DISPLAY 0.872340 (-6975 3100);
PAINT GREEN (-6975 3100);
DISPLAY INVISIBLE (-6975 3100);
FORCEPROP 2 LAST CDS_LIB standard
J 0
(-6650 3225);
DISPLAY INVISIBLE (-6650 3225);
FORCEADD OFFPAGE..4
R 2
(-6650 3175);
FORCEPROP 2 LAST $XR1 81 
J 0
(-6961 3175);
DISPLAY 0.638298 (-6961 3175);
PAINT MONO (-6961 3175);
FORCEPROP 2 LAST $XR0 54 
J 0
(-6871 3175);
DISPLAY 0.638298 (-6871 3175);
PAINT MONO (-6871 3175);
FORCEPROP 2 LAST PATH I248
J 0
(-6900 3225);
DISPLAY 1.021277 (-6900 3225);
DISPLAY INVISIBLE (-6900 3225);
FORCEPROP 1 LAST COMMENT_BODY TRUE
J 2
(-6625 3075);
DISPLAY 0.872340 (-6625 3075);
PAINT GREEN (-6625 3075);
DISPLAY INVISIBLE (-6625 3075);
FORCEPROP 1 LAST OFFPAGE TRUE
J 2
(-6975 3050);
DISPLAY 0.872340 (-6975 3050);
PAINT GREEN (-6975 3050);
DISPLAY INVISIBLE (-6975 3050);
FORCEPROP 2 LAST CDS_LIB standard
J 0
(-6650 3175);
DISPLAY INVISIBLE (-6650 3175);
FORCEADD OFFPAGE..2
R 2
(-6650 3025);
FORCEPROP 2 LAST $XR1 81 
J 0
(-6964 3025);
DISPLAY 0.638298 (-6964 3025);
PAINT MONO (-6964 3025);
FORCEPROP 2 LAST $XR0 54 
J 0
(-6874 3025);
DISPLAY 0.638298 (-6874 3025);
PAINT MONO (-6874 3025);
FORCEPROP 2 LAST PATH I249
J 0
(-6850 3075);
DISPLAY 1.021277 (-6850 3075);
DISPLAY INVISIBLE (-6850 3075);
FORCEPROP 1 LAST COMMENT_BODY TRUE
J 2
(-6605 2930);
DISPLAY 0.872340 (-6605 2930);
PAINT GREEN (-6605 2930);
DISPLAY INVISIBLE (-6605 2930);
FORCEPROP 1 LAST OFFPAGE TRUE
J 2
(-6975 2900);
DISPLAY 0.872340 (-6975 2900);
PAINT GREEN (-6975 2900);
DISPLAY INVISIBLE (-6975 2900);
FORCEPROP 2 LAST CDS_LIB standard
J 0
(-6650 3025);
DISPLAY INVISIBLE (-6650 3025);
FORCEADD OFFPAGE..2
R 2
(-6650 2975);
FORCEPROP 2 LAST $XR1 81 
J 0
(-6964 2975);
DISPLAY 0.638298 (-6964 2975);
PAINT MONO (-6964 2975);
FORCEPROP 2 LAST $XR0 54 
J 0
(-6874 2975);
DISPLAY 0.638298 (-6874 2975);
PAINT MONO (-6874 2975);
FORCEPROP 2 LAST PATH I250
J 0
(-6850 3025);
DISPLAY 1.021277 (-6850 3025);
DISPLAY INVISIBLE (-6850 3025);
FORCEPROP 1 LAST COMMENT_BODY TRUE
J 2
(-6605 2880);
DISPLAY 0.872340 (-6605 2880);
PAINT GREEN (-6605 2880);
DISPLAY INVISIBLE (-6605 2880);
FORCEPROP 1 LAST OFFPAGE TRUE
J 2
(-6975 2850);
DISPLAY 0.872340 (-6975 2850);
PAINT GREEN (-6975 2850);
DISPLAY INVISIBLE (-6975 2850);
FORCEPROP 2 LAST CDS_LIB standard
J 0
(-6650 2975);
DISPLAY INVISIBLE (-6650 2975);
FORCEADD OFFPAGE..2
R 2
(-6650 2875);
FORCEPROP 2 LAST $XR1 81 
J 0
(-6964 2875);
DISPLAY 0.638298 (-6964 2875);
PAINT MONO (-6964 2875);
FORCEPROP 2 LAST $XR0 54 
J 0
(-6874 2875);
DISPLAY 0.638298 (-6874 2875);
PAINT MONO (-6874 2875);
FORCEPROP 2 LAST PATH I251
J 0
(-6850 2925);
DISPLAY 1.021277 (-6850 2925);
DISPLAY INVISIBLE (-6850 2925);
FORCEPROP 1 LAST COMMENT_BODY TRUE
J 2
(-6605 2780);
DISPLAY 0.872340 (-6605 2780);
PAINT GREEN (-6605 2780);
DISPLAY INVISIBLE (-6605 2780);
FORCEPROP 1 LAST OFFPAGE TRUE
J 2
(-6975 2750);
DISPLAY 0.872340 (-6975 2750);
PAINT GREEN (-6975 2750);
DISPLAY INVISIBLE (-6975 2750);
FORCEPROP 2 LAST CDS_LIB standard
J 0
(-6650 2875);
DISPLAY INVISIBLE (-6650 2875);
FORCEADD OFFPAGE..2
R 2
(-6650 2925);
FORCEPROP 2 LAST $XR1 81 
J 0
(-6964 2925);
DISPLAY 0.638298 (-6964 2925);
PAINT MONO (-6964 2925);
FORCEPROP 2 LAST $XR0 54 
J 0
(-6874 2925);
DISPLAY 0.638298 (-6874 2925);
PAINT MONO (-6874 2925);
FORCEPROP 2 LAST PATH I252
J 0
(-6850 2975);
DISPLAY 1.021277 (-6850 2975);
DISPLAY INVISIBLE (-6850 2975);
FORCEPROP 1 LAST COMMENT_BODY TRUE
J 2
(-6605 2830);
DISPLAY 0.872340 (-6605 2830);
PAINT GREEN (-6605 2830);
DISPLAY INVISIBLE (-6605 2830);
FORCEPROP 1 LAST OFFPAGE TRUE
J 2
(-6975 2800);
DISPLAY 0.872340 (-6975 2800);
PAINT GREEN (-6975 2800);
DISPLAY INVISIBLE (-6975 2800);
FORCEPROP 2 LAST CDS_LIB standard
J 0
(-6650 2925);
DISPLAY INVISIBLE (-6650 2925);
FORCEADD OFFPAGE..2
R 2
(-6650 2775);
FORCEPROP 2 LAST $XR1 81 
J 0
(-6964 2775);
DISPLAY 0.638298 (-6964 2775);
PAINT MONO (-6964 2775);
FORCEPROP 2 LAST $XR0 54 
J 0
(-6874 2775);
DISPLAY 0.638298 (-6874 2775);
PAINT MONO (-6874 2775);
FORCEPROP 2 LAST PATH I253
J 0
(-6850 2825);
DISPLAY 1.021277 (-6850 2825);
DISPLAY INVISIBLE (-6850 2825);
FORCEPROP 1 LAST COMMENT_BODY TRUE
J 2
(-6605 2680);
DISPLAY 0.872340 (-6605 2680);
PAINT GREEN (-6605 2680);
DISPLAY INVISIBLE (-6605 2680);
FORCEPROP 1 LAST OFFPAGE TRUE
J 2
(-6975 2650);
DISPLAY 0.872340 (-6975 2650);
PAINT GREEN (-6975 2650);
DISPLAY INVISIBLE (-6975 2650);
FORCEPROP 2 LAST CDS_LIB standard
J 0
(-6650 2775);
DISPLAY INVISIBLE (-6650 2775);
FORCEADD OFFPAGE..2
R 2
(-6650 2725);
FORCEPROP 2 LAST $XR1 81 
J 0
(-6964 2725);
DISPLAY 0.638298 (-6964 2725);
PAINT MONO (-6964 2725);
FORCEPROP 2 LAST $XR0 54 
J 0
(-6874 2725);
DISPLAY 0.638298 (-6874 2725);
PAINT MONO (-6874 2725);
FORCEPROP 2 LAST PATH I254
J 0
(-6850 2775);
DISPLAY 1.021277 (-6850 2775);
DISPLAY INVISIBLE (-6850 2775);
FORCEPROP 1 LAST COMMENT_BODY TRUE
J 2
(-6605 2630);
DISPLAY 0.872340 (-6605 2630);
PAINT GREEN (-6605 2630);
DISPLAY INVISIBLE (-6605 2630);
FORCEPROP 1 LAST OFFPAGE TRUE
J 2
(-6975 2600);
DISPLAY 0.872340 (-6975 2600);
PAINT GREEN (-6975 2600);
DISPLAY INVISIBLE (-6975 2600);
FORCEPROP 2 LAST CDS_LIB standard
J 0
(-6650 2725);
DISPLAY INVISIBLE (-6650 2725);
FORCEADD OFFPAGE..2
R 2
(-6650 2675);
FORCEPROP 2 LAST $XR1 81 
J 0
(-6964 2675);
DISPLAY 0.638298 (-6964 2675);
PAINT MONO (-6964 2675);
FORCEPROP 2 LAST $XR0 54 
J 0
(-6874 2675);
DISPLAY 0.638298 (-6874 2675);
PAINT MONO (-6874 2675);
FORCEPROP 2 LAST PATH I255
J 0
(-6850 2725);
DISPLAY 1.021277 (-6850 2725);
DISPLAY INVISIBLE (-6850 2725);
FORCEPROP 1 LAST COMMENT_BODY TRUE
J 2
(-6605 2580);
DISPLAY 0.872340 (-6605 2580);
PAINT GREEN (-6605 2580);
DISPLAY INVISIBLE (-6605 2580);
FORCEPROP 1 LAST OFFPAGE TRUE
J 2
(-6975 2550);
DISPLAY 0.872340 (-6975 2550);
PAINT GREEN (-6975 2550);
DISPLAY INVISIBLE (-6975 2550);
FORCEPROP 2 LAST CDS_LIB standard
J 0
(-6650 2675);
DISPLAY INVISIBLE (-6650 2675);
FORCEADD OFFPAGE..2
R 2
(-7025 2575);
FORCEPROP 2 LAST $XR0 186 
J 0
(-7280 2575);
DISPLAY 0.638298 (-7280 2575);
PAINT MONO (-7280 2575);
FORCEPROP 2 LAST PATH I256
J 0
(-7275 2625);
DISPLAY 1.021277 (-7275 2625);
DISPLAY INVISIBLE (-7275 2625);
FORCEPROP 1 LAST COMMENT_BODY TRUE
J 2
(-6980 2480);
DISPLAY 0.872340 (-6980 2480);
PAINT GREEN (-6980 2480);
DISPLAY INVISIBLE (-6980 2480);
FORCEPROP 1 LAST OFFPAGE TRUE
J 2
(-7350 2450);
DISPLAY 0.872340 (-7350 2450);
PAINT GREEN (-7350 2450);
DISPLAY INVISIBLE (-7350 2450);
FORCEPROP 2 LAST CDS_LIB standard
J 0
(-7025 2575);
DISPLAY INVISIBLE (-7025 2575);
FORCEADD OFFPAGE..2
R 2
(-7025 2525);
FORCEPROP 2 LAST $XR0 193 
J 0
(-7280 2525);
DISPLAY 0.638298 (-7280 2525);
PAINT MONO (-7280 2525);
FORCEPROP 2 LAST PATH I257
J 0
(-7275 2575);
DISPLAY 1.021277 (-7275 2575);
DISPLAY INVISIBLE (-7275 2575);
FORCEPROP 1 LAST COMMENT_BODY TRUE
J 2
(-6980 2430);
DISPLAY 0.872340 (-6980 2430);
PAINT GREEN (-6980 2430);
DISPLAY INVISIBLE (-6980 2430);
FORCEPROP 1 LAST OFFPAGE TRUE
J 2
(-7350 2400);
DISPLAY 0.872340 (-7350 2400);
PAINT GREEN (-7350 2400);
DISPLAY INVISIBLE (-7350 2400);
FORCEPROP 2 LAST CDS_LIB standard
J 0
(-7025 2525);
DISPLAY INVISIBLE (-7025 2525);
FORCEADD OFFPAGE..2
R 2
(-7025 2475);
FORCEPROP 2 LAST $XR1 200 
J 0
(-7400 2475);
DISPLAY 0.638298 (-7400 2475);
PAINT MONO (-7400 2475);
FORCEPROP 2 LAST $XR0 193 
J 0
(-7280 2475);
DISPLAY 0.638298 (-7280 2475);
PAINT MONO (-7280 2475);
FORCEPROP 2 LAST PATH I258
J 0
(-7275 2525);
DISPLAY 1.021277 (-7275 2525);
DISPLAY INVISIBLE (-7275 2525);
FORCEPROP 1 LAST COMMENT_BODY TRUE
J 2
(-6980 2380);
DISPLAY 0.872340 (-6980 2380);
PAINT GREEN (-6980 2380);
DISPLAY INVISIBLE (-6980 2380);
FORCEPROP 1 LAST OFFPAGE TRUE
J 2
(-7350 2350);
DISPLAY 0.872340 (-7350 2350);
PAINT GREEN (-7350 2350);
DISPLAY INVISIBLE (-7350 2350);
FORCEPROP 2 LAST CDS_LIB standard
J 0
(-7025 2475);
DISPLAY INVISIBLE (-7025 2475);
FORCEADD OFFPAGE..2
R 2
(-7025 2425);
FORCEPROP 2 LAST $XR0 202 
J 0
(-7280 2425);
DISPLAY 0.638298 (-7280 2425);
PAINT MONO (-7280 2425);
FORCEPROP 2 LAST PATH I259
J 0
(-7275 2475);
DISPLAY 1.021277 (-7275 2475);
DISPLAY INVISIBLE (-7275 2475);
FORCEPROP 1 LAST COMMENT_BODY TRUE
J 2
(-6980 2330);
DISPLAY 0.872340 (-6980 2330);
PAINT GREEN (-6980 2330);
DISPLAY INVISIBLE (-6980 2330);
FORCEPROP 1 LAST OFFPAGE TRUE
J 2
(-7350 2300);
DISPLAY 0.872340 (-7350 2300);
PAINT GREEN (-7350 2300);
DISPLAY INVISIBLE (-7350 2300);
FORCEPROP 2 LAST CDS_LIB standard
J 0
(-7025 2425);
DISPLAY INVISIBLE (-7025 2425);
FORCEADD OFFPAGE..2
R 2
(-7025 2325);
FORCEPROP 2 LAST $XR0 193 
J 0
(-7280 2325);
DISPLAY 0.638298 (-7280 2325);
PAINT MONO (-7280 2325);
FORCEPROP 2 LAST PATH I260
J 0
(-7275 2375);
DISPLAY 1.021277 (-7275 2375);
DISPLAY INVISIBLE (-7275 2375);
FORCEPROP 1 LAST COMMENT_BODY TRUE
J 2
(-6980 2230);
DISPLAY 0.872340 (-6980 2230);
PAINT GREEN (-6980 2230);
DISPLAY INVISIBLE (-6980 2230);
FORCEPROP 1 LAST OFFPAGE TRUE
J 2
(-7350 2200);
DISPLAY 0.872340 (-7350 2200);
PAINT GREEN (-7350 2200);
DISPLAY INVISIBLE (-7350 2200);
FORCEPROP 2 LAST CDS_LIB standard
J 0
(-7025 2325);
DISPLAY INVISIBLE (-7025 2325);
FORCEADD OFFPAGE..2
R 2
(-7025 2225);
FORCEPROP 2 LAST $XR0 186 
J 0
(-7280 2225);
DISPLAY 0.638298 (-7280 2225);
PAINT MONO (-7280 2225);
FORCEPROP 2 LAST PATH I261
J 0
(-7275 2275);
DISPLAY 1.021277 (-7275 2275);
DISPLAY INVISIBLE (-7275 2275);
FORCEPROP 1 LAST COMMENT_BODY TRUE
J 2
(-6980 2130);
DISPLAY 0.872340 (-6980 2130);
PAINT GREEN (-6980 2130);
DISPLAY INVISIBLE (-6980 2130);
FORCEPROP 1 LAST OFFPAGE TRUE
J 2
(-7350 2100);
DISPLAY 0.872340 (-7350 2100);
PAINT GREEN (-7350 2100);
DISPLAY INVISIBLE (-7350 2100);
FORCEPROP 2 LAST CDS_LIB standard
J 0
(-7025 2225);
DISPLAY INVISIBLE (-7025 2225);
FORCEADD OFFPAGE..2
R 2
(-7025 2275);
FORCEPROP 2 LAST $XR0 193 
J 0
(-7280 2275);
DISPLAY 0.638298 (-7280 2275);
PAINT MONO (-7280 2275);
FORCEPROP 2 LAST PATH I262
J 0
(-7275 2325);
DISPLAY 1.021277 (-7275 2325);
DISPLAY INVISIBLE (-7275 2325);
FORCEPROP 1 LAST COMMENT_BODY TRUE
J 2
(-6980 2180);
DISPLAY 0.872340 (-6980 2180);
PAINT GREEN (-6980 2180);
DISPLAY INVISIBLE (-6980 2180);
FORCEPROP 1 LAST OFFPAGE TRUE
J 2
(-7350 2150);
DISPLAY 0.872340 (-7350 2150);
PAINT GREEN (-7350 2150);
DISPLAY INVISIBLE (-7350 2150);
FORCEPROP 2 LAST CDS_LIB standard
J 0
(-7025 2275);
DISPLAY INVISIBLE (-7025 2275);
FORCEADD OFFPAGE..2
R 2
(-7025 2175);
FORCEPROP 2 LAST $XR0 200 
J 0
(-7280 2175);
DISPLAY 0.638298 (-7280 2175);
PAINT MONO (-7280 2175);
FORCEPROP 2 LAST PATH I263
J 0
(-7275 2225);
DISPLAY 1.021277 (-7275 2225);
DISPLAY INVISIBLE (-7275 2225);
FORCEPROP 1 LAST COMMENT_BODY TRUE
J 2
(-6980 2080);
DISPLAY 0.872340 (-6980 2080);
PAINT GREEN (-6980 2080);
DISPLAY INVISIBLE (-6980 2080);
FORCEPROP 1 LAST OFFPAGE TRUE
J 2
(-7350 2050);
DISPLAY 0.872340 (-7350 2050);
PAINT GREEN (-7350 2050);
DISPLAY INVISIBLE (-7350 2050);
FORCEPROP 2 LAST CDS_LIB standard
J 0
(-7025 2175);
DISPLAY INVISIBLE (-7025 2175);
FORCEADD TP..1
R 6
(-6825 1900);
FORCEPROP 1 LAST LOCATION TP12
J 1
(-6825 1802);
DISPLAY 0.489362 (-6825 1802);
PAINT SKYBLUE (-6825 1802);
FORCEPROP 0 LAST $SEC 1
J 0
(-6850 1875);
DISPLAY 0.680851 (-6850 1875);
PAINT MONO (-6850 1875);
DISPLAY INVISIBLE (-6850 1875);
FORCEPROP 0 LAST CDS_SEC 1
J 0
(-6850 1875);
DISPLAY 1.021277 (-6850 1875);
DISPLAY INVISIBLE (-6850 1875);
FORCEPROP 0 LASTPIN (-6825 1950) $PN 1
R 1
J 0
(-6835 1960);
DISPLAY 0.489362 (-6835 1960);
PAINT MONO (-6835 1960);
FORCEPROP 1 LAST MATERIAL NA
J 0
(-6850 1852);
DISPLAY 0.489362 (-6850 1852);
PAINT SKYBLUE (-6850 1852);
FORCEPROP 2 LAST CDS_LIB pure_quanta
J 0
(-6825 1900);
DISPLAY INVISIBLE (-6825 1900);
FORCEPROP 1 LASTPIN (-6825 1950) $PIN_NUMBER ?
J 2
(-6775 1950);
DISPLAY 0.702128 (-6775 1950);
PAINT MONO (-6775 1950);
DISPLAY INVISIBLE (-6775 1950);
FORCEPROP 1 LAST PATH I272
J 1
(-6820 1855);
DISPLAY 0.446809 (-6820 1855);
PAINT GREEN (-6820 1855);
DISPLAY INVISIBLE (-6820 1855);
FORCEPROP 1 LAST PART_NUMBER TP30
J 1
(-6770 1924);
DISPLAY 0.446809 (-6770 1924);
PAINT SKYBLUE (-6770 1924);
DISPLAY INVISIBLE (-6770 1924);
FORCEPROP 1 LAST PACK_TYPE TP
J 1
(-6770 1944);
DISPLAY 0.446809 (-6770 1944);
PAINT SKYBLUE (-6770 1944);
DISPLAY INVISIBLE (-6770 1944);
FORCEADD TP..1
R 6
(-6900 1900);
FORCEPROP 1 LAST LOCATION TP11
J 1
(-6900 1802);
DISPLAY 0.489362 (-6900 1802);
PAINT SKYBLUE (-6900 1802);
FORCEPROP 0 LAST $SEC 1
J 0
(-6925 1875);
DISPLAY 0.680851 (-6925 1875);
PAINT MONO (-6925 1875);
DISPLAY INVISIBLE (-6925 1875);
FORCEPROP 0 LAST CDS_SEC 1
J 0
(-6925 1875);
DISPLAY 1.021277 (-6925 1875);
DISPLAY INVISIBLE (-6925 1875);
FORCEPROP 0 LASTPIN (-6900 1950) $PN 1
R 1
J 0
(-6910 1960);
DISPLAY 0.489362 (-6910 1960);
PAINT MONO (-6910 1960);
FORCEPROP 1 LAST MATERIAL NA
J 0
(-6925 1852);
DISPLAY 0.489362 (-6925 1852);
PAINT SKYBLUE (-6925 1852);
FORCEPROP 2 LAST CDS_LIB pure_quanta
J 0
(-6900 1900);
DISPLAY INVISIBLE (-6900 1900);
FORCEPROP 1 LASTPIN (-6900 1950) $PIN_NUMBER ?
J 2
(-6850 1950);
DISPLAY 0.702128 (-6850 1950);
PAINT MONO (-6850 1950);
DISPLAY INVISIBLE (-6850 1950);
FORCEPROP 1 LAST PATH I273
J 1
(-6895 1855);
DISPLAY 0.446809 (-6895 1855);
PAINT GREEN (-6895 1855);
DISPLAY INVISIBLE (-6895 1855);
FORCEPROP 1 LAST PART_NUMBER TP30
J 1
(-6845 1924);
DISPLAY 0.446809 (-6845 1924);
PAINT SKYBLUE (-6845 1924);
DISPLAY INVISIBLE (-6845 1924);
FORCEPROP 1 LAST PACK_TYPE TP
J 1
(-6845 1944);
DISPLAY 0.446809 (-6845 1944);
PAINT SKYBLUE (-6845 1944);
DISPLAY INVISIBLE (-6845 1944);
FORCEADD OFFPAGE..2
R 2
(-7025 2075);
FORCEPROP 2 LAST $XR0 202 
J 0
(-7280 2075);
DISPLAY 0.638298 (-7280 2075);
PAINT MONO (-7280 2075);
FORCEPROP 2 LAST PATH I274
J 0
(-7275 2125);
DISPLAY 1.021277 (-7275 2125);
DISPLAY INVISIBLE (-7275 2125);
FORCEPROP 1 LAST COMMENT_BODY TRUE
J 2
(-6980 1980);
DISPLAY 0.872340 (-6980 1980);
PAINT GREEN (-6980 1980);
DISPLAY INVISIBLE (-6980 1980);
FORCEPROP 1 LAST OFFPAGE TRUE
J 2
(-7350 1950);
DISPLAY 0.872340 (-7350 1950);
PAINT GREEN (-7350 1950);
DISPLAY INVISIBLE (-7350 1950);
FORCEPROP 2 LAST CDS_LIB standard
J 0
(-7025 2075);
DISPLAY INVISIBLE (-7025 2075);
FORCEADD OFFPAGE..2
R 2
(-7025 2025);
FORCEPROP 2 LAST $XR0 186 
J 0
(-7280 2025);
DISPLAY 0.638298 (-7280 2025);
PAINT MONO (-7280 2025);
FORCEPROP 2 LAST PATH I275
J 0
(-7275 2075);
DISPLAY 1.021277 (-7275 2075);
DISPLAY INVISIBLE (-7275 2075);
FORCEPROP 1 LAST COMMENT_BODY TRUE
J 2
(-6980 1930);
DISPLAY 0.872340 (-6980 1930);
PAINT GREEN (-6980 1930);
DISPLAY INVISIBLE (-6980 1930);
FORCEPROP 1 LAST OFFPAGE TRUE
J 2
(-7350 1900);
DISPLAY 0.872340 (-7350 1900);
PAINT GREEN (-7350 1900);
DISPLAY INVISIBLE (-7350 1900);
FORCEPROP 2 LAST CDS_LIB standard
J 0
(-7025 2025);
DISPLAY INVISIBLE (-7025 2025);
FORCEADD UNIVERSAL_POWER..1
(-8750 5000);
FORCEPROP 3 LASTPIN (-8750 4950) SIG_NAME PVDD18_S5_P1\g
J 0
(-8740 4960);
DISPLAY 0.659574 (-8740 4960);
PAINT MONO (-8740 4960);
DISPLAY INVISIBLE (-8740 4960);
FORCEPROP 1 LAST HDL_POWER PVDD18_S5_P1
J 1
(-8750 5050);
DISPLAY 0.489362 (-8750 5050);
PAINT GREEN (-8750 5050);
FORCEPROP 2 LAST CDS_LIB pure_quanta_power
J 0
(-8750 5000);
DISPLAY INVISIBLE (-8750 5000);
FORCEPROP 1 LAST PATH I286
J 0
(-8700 5025);
DISPLAY 0.872340 (-8700 5025);
PAINT AQUA (-8700 5025);
DISPLAY INVISIBLE (-8700 5025);
FORCEADD GND..1
(-8625 4275);
FORCEPROP 3 LASTPIN (-8625 4325) SIG_NAME GND\g
J 0
(-8615 4335);
DISPLAY 0.659574 (-8615 4335);
PAINT MONO (-8615 4335);
DISPLAY INVISIBLE (-8615 4335);
FORCEPROP 1 LAST SIZE 1B
J 0
(-8550 4225);
DISPLAY 0.872340 (-8550 4225);
PAINT GREEN (-8550 4225);
DISPLAY INVISIBLE (-8550 4225);
FORCEPROP 2 LAST CDS_LIB pure_quanta_power
J 0
(-8625 4275);
DISPLAY INVISIBLE (-8625 4275);
FORCEPROP 1 LAST PATH I289
J 0
(-8550 4275);
DISPLAY 0.872340 (-8550 4275);
PAINT AQUA (-8550 4275);
DISPLAY INVISIBLE (-8550 4275);
FORCEPROP 1 LAST HDL_POWER GND
J 0
(-8625 4425);
DISPLAY 0.872340 (-8625 4425);
PAINT GREEN (-8625 4425);
DISPLAY INVISIBLE (-8625 4425);
FORCEADD GND..1
(-8750 4275);
FORCEPROP 3 LASTPIN (-8750 4325) SIG_NAME GND\g
J 0
(-8740 4335);
DISPLAY 0.659574 (-8740 4335);
PAINT MONO (-8740 4335);
DISPLAY INVISIBLE (-8740 4335);
FORCEPROP 1 LAST SIZE 1B
J 0
(-8675 4225);
DISPLAY 0.872340 (-8675 4225);
PAINT GREEN (-8675 4225);
DISPLAY INVISIBLE (-8675 4225);
FORCEPROP 2 LAST CDS_LIB pure_quanta_power
J 0
(-8750 4275);
DISPLAY INVISIBLE (-8750 4275);
FORCEPROP 1 LAST PATH I291
J 0
(-8675 4275);
DISPLAY 0.872340 (-8675 4275);
PAINT AQUA (-8675 4275);
DISPLAY INVISIBLE (-8675 4275);
FORCEPROP 1 LAST HDL_POWER GND
J 0
(-8750 4425);
DISPLAY 0.872340 (-8750 4425);
PAINT GREEN (-8750 4425);
DISPLAY INVISIBLE (-8750 4425);
FORCEADD SCONN8_G802M0083150RD3EU..1
(-1025 2525);
FORCEPROP 1 LAST LOCATION J49
J 0
(-1150 2940);
DISPLAY 0.489362 (-1150 2940);
PAINT SKYBLUE (-1150 2940);
FORCEPROP 0 LAST $SEC 1
J 0
(-1150 2975);
DISPLAY 0.680851 (-1150 2975);
PAINT MONO (-1150 2975);
DISPLAY INVISIBLE (-1150 2975);
FORCEPROP 0 LAST CDS_SEC 1
J 0
(-1075 2900);
DISPLAY 1.021277 (-1075 2900);
DISPLAY INVISIBLE (-1075 2900);
FORCEPROP 0 LASTPIN (-1300 2600) $PN 1
J 2
(-1310 2610);
DISPLAY 0.489362 (-1310 2610);
PAINT MONO (-1310 2610);
FORCEPROP 0 LASTPIN (-750 2600) $PN 2
J 0
(-740 2610);
DISPLAY 0.489362 (-740 2610);
PAINT MONO (-740 2610);
FORCEPROP 0 LASTPIN (-1300 2550) $PN 3
J 2
(-1310 2560);
DISPLAY 0.489362 (-1310 2560);
PAINT MONO (-1310 2560);
FORCEPROP 0 LASTPIN (-750 2550) $PN 4
J 0
(-740 2560);
DISPLAY 0.489362 (-740 2560);
PAINT MONO (-740 2560);
FORCEPROP 0 LASTPIN (-1300 2500) $PN 5
J 2
(-1310 2510);
DISPLAY 0.489362 (-1310 2510);
PAINT MONO (-1310 2510);
FORCEPROP 0 LASTPIN (-750 2500) $PN 6
J 0
(-740 2510);
DISPLAY 0.489362 (-740 2510);
PAINT MONO (-740 2510);
FORCEPROP 0 LASTPIN (-1300 2450) $PN 7
J 2
(-1310 2460);
DISPLAY 0.489362 (-1310 2460);
PAINT MONO (-1310 2460);
FORCEPROP 0 LASTPIN (-750 2450) $PN 8
J 0
(-740 2460);
DISPLAY 0.489362 (-740 2460);
PAINT MONO (-740 2460);
FORCEPROP 2 LAST PART_TYPE SMLF
J 0
(-1150 2850);
DISPLAY 1.021277 (-1150 2850);
FORCEPROP 1 LAST MATERIAL IO
J 0
(-1150 2666);
DISPLAY 0.489362 (-1150 2666);
PAINT SKYBLUE (-1150 2666);
FORCEPROP 2 LAST VALUE SCONN8_G802M0083150RD3EU
J 0
(-1150 2800);
DISPLAY 0.489362 (-1150 2800);
PAINT SKYBLUE (-1150 2800);
FORCEPROP 1 LAST PART_NUMBER DFHD08MS351
J 0
(-1150 2725);
DISPLAY 0.489362 (-1150 2725);
PAINT SKYBLUE (-1150 2725);
FORCEPROP 2 LAST CDS_LIB pure_quanta
J 0
(-1025 2525);
DISPLAY INVISIBLE (-1025 2525);
FORCEPROP 1 LAST NEEDS_NO_SIZE TRUE
J 0
(-1025 2525);
DISPLAY 0.723404 (-1025 2525);
PAINT GREEN (-1025 2525);
DISPLAY INVISIBLE (-1025 2525);
FORCEPROP 1 LAST CDS_LMAN_SYM_OUTLINE -125,125,125,-125
J 0
(-1025 2525);
DISPLAY 0.468085 (-1025 2525);
PAINT GREEN (-1025 2525);
DISPLAY INVISIBLE (-1025 2525);
FORCEPROP 1 LAST PATH I302
J 0
(-1025 2525);
DISPLAY 0.723404 (-1025 2525);
PAINT GREEN (-1025 2525);
DISPLAY INVISIBLE (-1025 2525);
FORCEADD Q_RES..2
(-6725 1325);
FORCEPROP 1 LAST LOCATION R528
J 0
(-6700 1425);
DISPLAY 0.489362 (-6700 1425);
PAINT SKYBLUE (-6700 1425);
FORCEPROP 0 LAST $SEC 1
J 0
(-6700 1475);
DISPLAY 0.680851 (-6700 1475);
PAINT MONO (-6700 1475);
DISPLAY INVISIBLE (-6700 1475);
FORCEPROP 0 LAST CDS_SEC 1
J 0
(-6700 1475);
DISPLAY 1.021277 (-6700 1475);
DISPLAY INVISIBLE (-6700 1475);
FORCEPROP 1 LASTPIN (-6725 1425) $PN 1
J 0
(-6720 1387);
DISPLAY 0.489362 (-6720 1387);
PAINT MONO (-6720 1387);
FORCEPROP 1 LASTPIN (-6725 1225) $PN 2
J 0
(-6720 1235);
DISPLAY 0.489362 (-6720 1235);
PAINT MONO (-6720 1235);
FORCEPROP 1 LAST WATTAGE 1/16W
J 0
(-6700 1275);
DISPLAY 0.489362 (-6700 1275);
PAINT SKYBLUE (-6700 1275);
FORCEPROP 1 LAST MATERIAL CHIP
J 0
(-6700 1225);
DISPLAY 0.489362 (-6700 1225);
PAINT SKYBLUE (-6700 1225);
FORCEPROP 1 LAST TOLERANCE 5%
J 0
(-6700 1325);
DISPLAY 0.489362 (-6700 1325);
PAINT SKYBLUE (-6700 1325);
FORCEPROP 1 LAST VALUE 1K
J 0
(-6700 1375);
DISPLAY 0.489362 (-6700 1375);
PAINT SKYBLUE (-6700 1375);
FORCEPROP 1 LAST PART_NUMBER TMP_QCS21002JB34
J 0
(-6700 1125);
DISPLAY 0.489362 (-6700 1125);
PAINT SKYBLUE (-6700 1125);
FORCEPROP 1 LAST PACK_TYPE 0402LF
J 0
(-6700 1175);
DISPLAY 0.489362 (-6700 1175);
PAINT SKYBLUE (-6700 1175);
FORCEPROP 2 LAST CDS_LIB pure_quanta
J 0
(-6725 1325);
DISPLAY INVISIBLE (-6725 1325);
FORCEPROP 1 LAST PATH I308
J 0
(-6675 1500);
DISPLAY 0.978723 (-6675 1500);
PAINT WHITE (-6675 1500);
DISPLAY INVISIBLE (-6675 1500);
FORCEADD Q_RES..2
(-7000 1325);
FORCEPROP 1 LAST LOCATION R527
J 0
(-6975 1425);
DISPLAY 0.489362 (-6975 1425);
PAINT SKYBLUE (-6975 1425);
FORCEPROP 2 LAST $SEC 1
J 0
(-6950 1550);
DISPLAY 0.680851 (-6950 1550);
PAINT MONO (-6950 1550);
DISPLAY INVISIBLE (-6950 1550);
FORCEPROP 2 LAST CDS_SEC 1
J 0
(-6950 1550);
DISPLAY 1.021277 (-6950 1550);
DISPLAY INVISIBLE (-6950 1550);
FORCEPROP 1 LASTPIN (-7000 1425) $PN 1
J 0
(-6995 1387);
DISPLAY 0.489362 (-6995 1387);
FORCEPROP 1 LASTPIN (-7000 1225) $PN 2
J 0
(-6995 1235);
DISPLAY 0.489362 (-6995 1235);
FORCEPROP 1 LAST WATTAGE 1/16W
J 0
(-6975 1275);
DISPLAY 0.489362 (-6975 1275);
PAINT SKYBLUE (-6975 1275);
FORCEPROP 1 LAST MATERIAL CHIP
J 0
(-6975 1225);
DISPLAY 0.489362 (-6975 1225);
PAINT SKYBLUE (-6975 1225);
FORCEPROP 1 LAST TOLERANCE 5%
J 0
(-6975 1325);
DISPLAY 0.489362 (-6975 1325);
PAINT SKYBLUE (-6975 1325);
FORCEPROP 1 LAST VALUE 1K
J 0
(-6975 1375);
DISPLAY 0.489362 (-6975 1375);
PAINT SKYBLUE (-6975 1375);
FORCEPROP 1 LAST PACK_TYPE 0402LF
J 0
(-6975 1175);
DISPLAY 0.489362 (-6975 1175);
PAINT SKYBLUE (-6975 1175);
FORCEPROP 2 LAST CDS_LIB pure_quanta
J 0
(-7000 1325);
DISPLAY INVISIBLE (-7000 1325);
FORCEPROP 1 LAST PATH I309
J 0
(-6950 1500);
DISPLAY 0.978723 (-6950 1500);
PAINT WHITE (-6950 1500);
DISPLAY INVISIBLE (-6950 1500);
FORCEPROP 1 LAST PART_NUMBER TMP_QCS21002JB34
J 0
(-6960 1200);
DISPLAY 0.617021 (-6960 1200);
PAINT SKYBLUE (-6960 1200);
DISPLAY INVISIBLE (-6960 1200);
FORCEADD Q_CAP..1
(-6725 625);
FORCEPROP 1 LAST LOCATION C235
J 0
(-6675 725);
DISPLAY 0.489362 (-6675 725);
PAINT SKYBLUE (-6675 725);
FORCEPROP 0 LAST $SEC 1
J 0
(-6675 775);
DISPLAY 0.680851 (-6675 775);
PAINT MONO (-6675 775);
DISPLAY INVISIBLE (-6675 775);
FORCEPROP 0 LAST CDS_SEC 1
J 0
(-6675 775);
DISPLAY 1.021277 (-6675 775);
DISPLAY INVISIBLE (-6675 775);
FORCEPROP 1 LASTPIN (-6725 725) $PN 1
J 0
(-6715 705);
DISPLAY 0.489362 (-6715 705);
PAINT MONO (-6715 705);
FORCEPROP 1 LASTPIN (-6725 525) $PN 2
J 0
(-6715 505);
DISPLAY 0.489362 (-6715 505);
PAINT MONO (-6715 505);
FORCEPROP 1 LAST MATERIAL EMPTY
J 0
(-6675 425);
DISPLAY 0.489362 (-6675 425);
PAINT RED (-6675 425);
FORCEPROP 1 LAST TOLERANCE 10%
J 0
(-6675 575);
DISPLAY 0.489362 (-6675 575);
PAINT SKYBLUE (-6675 575);
FORCEPROP 1 LAST VALUE 0.001UF
J 0
(-6675 675);
DISPLAY 0.489362 (-6675 675);
PAINT SKYBLUE (-6675 675);
FORCEPROP 1 LAST PART_NUMBER CH30106KB19
J 0
(-6675 525);
DISPLAY 0.489362 (-6675 525);
PAINT SKYBLUE (-6675 525);
FORCEPROP 1 LAST VOLTAGE 50V
J 0
(-6675 625);
DISPLAY 0.489362 (-6675 625);
PAINT SKYBLUE (-6675 625);
FORCEPROP 1 LAST PACK_TYPE C0402
J 0
(-6675 475);
DISPLAY 0.489362 (-6675 475);
PAINT SKYBLUE (-6675 475);
FORCEPROP 2 LAST CDS_LIB pure_quanta
J 0
(-6725 625);
DISPLAY INVISIBLE (-6725 625);
FORCEPROP 1 LAST PATH I310
J 0
(-6675 775);
DISPLAY 0.978723 (-6675 775);
PAINT WHITE (-6675 775);
DISPLAY INVISIBLE (-6675 775);
FORCEADD Q_CAP..1
(-7000 625);
FORCEPROP 1 LAST LOCATION C234
J 0
(-6950 725);
DISPLAY 0.489362 (-6950 725);
PAINT SKYBLUE (-6950 725);
FORCEPROP 0 LAST $SEC 1
J 0
(-6950 775);
PAINT MONO (-6950 775);
DISPLAY INVISIBLE (-6950 775);
FORCEPROP 0 LAST CDS_SEC 1
J 0
(-6950 775);
PAINT MONO (-6950 775);
DISPLAY INVISIBLE (-6950 775);
FORCEPROP 1 LASTPIN (-7000 725) $PN 1
J 0
(-6990 705);
DISPLAY 0.489362 (-6990 705);
PAINT GREEN (-6990 705);
FORCEPROP 1 LASTPIN (-7000 525) $PN 2
J 0
(-6990 505);
DISPLAY 0.489362 (-6990 505);
PAINT GREEN (-6990 505);
FORCEPROP 1 LAST MATERIAL EMPTY
J 0
(-6950 425);
DISPLAY 0.489362 (-6950 425);
PAINT RED (-6950 425);
FORCEPROP 1 LAST TOLERANCE 10%
J 0
(-6950 575);
DISPLAY 0.489362 (-6950 575);
PAINT SKYBLUE (-6950 575);
FORCEPROP 1 LAST VALUE 0.001UF
J 0
(-6950 675);
DISPLAY 0.489362 (-6950 675);
PAINT SKYBLUE (-6950 675);
FORCEPROP 1 LAST VOLTAGE 50V
J 0
(-6950 625);
DISPLAY 0.489362 (-6950 625);
PAINT SKYBLUE (-6950 625);
FORCEPROP 1 LAST PACK_TYPE C0402
J 0
(-6950 475);
DISPLAY 0.489362 (-6950 475);
PAINT SKYBLUE (-6950 475);
FORCEPROP 2 LAST CDS_LIB pure_quanta
J 0
(-7000 625);
PAINT MONO (-7000 625);
DISPLAY INVISIBLE (-7000 625);
FORCEPROP 1 LAST PATH I311
J 0
(-6950 775);
DISPLAY 0.978723 (-6950 775);
PAINT WHITE (-6950 775);
DISPLAY INVISIBLE (-6950 775);
FORCEPROP 1 LAST PART_NUMBER CH30106KB19
J 0
(-6950 525);
DISPLAY 0.808511 (-6950 525);
PAINT SKYBLUE (-6950 525);
DISPLAY INVISIBLE (-6950 525);
FORCEADD GND..1
(-6725 325);
FORCEPROP 3 LASTPIN (-6725 375) SIG_NAME GND\g
J 0
(-6715 385);
DISPLAY 0.659574 (-6715 385);
PAINT MONO (-6715 385);
DISPLAY INVISIBLE (-6715 385);
FORCEPROP 1 LAST SIZE 1B
J 0
(-6650 275);
DISPLAY 0.872340 (-6650 275);
PAINT GREEN (-6650 275);
DISPLAY INVISIBLE (-6650 275);
FORCEPROP 2 LAST CDS_LIB pure_quanta_power
J 0
(-6725 325);
DISPLAY INVISIBLE (-6725 325);
FORCEPROP 1 LAST PATH I312
J 0
(-6650 325);
DISPLAY 0.872340 (-6650 325);
PAINT AQUA (-6650 325);
DISPLAY INVISIBLE (-6650 325);
FORCEPROP 1 LAST HDL_POWER GND
J 0
(-6725 475);
DISPLAY 0.872340 (-6725 475);
PAINT GREEN (-6725 475);
DISPLAY INVISIBLE (-6725 475);
FORCEADD GND..1
(-7000 325);
FORCEPROP 3 LASTPIN (-7000 375) SIG_NAME GND\g
J 0
(-6990 385);
DISPLAY 0.659574 (-6990 385);
PAINT MONO (-6990 385);
DISPLAY INVISIBLE (-6990 385);
FORCEPROP 2 LAST CDS_LIB pure_quanta_power
J 0
(-7000 325);
DISPLAY INVISIBLE (-7000 325);
FORCEPROP 1 LAST SIZE 1B
J 0
(-6925 275);
DISPLAY 0.872340 (-6925 275);
PAINT GREEN (-6925 275);
DISPLAY INVISIBLE (-6925 275);
FORCEPROP 1 LAST PATH I313
J 0
(-6925 325);
DISPLAY 0.872340 (-6925 325);
PAINT AQUA (-6925 325);
DISPLAY INVISIBLE (-6925 325);
FORCEPROP 1 LAST HDL_POWER GND
J 0
(-7000 475);
DISPLAY 0.872340 (-7000 475);
PAINT GREEN (-7000 475);
DISPLAY INVISIBLE (-7000 475);
FORCEADD Q_RES..2
(-7300 1325);
FORCEPROP 1 LAST LOCATION R526
J 0
(-7275 1425);
DISPLAY 0.489362 (-7275 1425);
PAINT SKYBLUE (-7275 1425);
FORCEPROP 2 LAST $SEC 1
J 0
(-7250 1550);
DISPLAY 0.680851 (-7250 1550);
PAINT MONO (-7250 1550);
DISPLAY INVISIBLE (-7250 1550);
FORCEPROP 2 LAST CDS_SEC 1
J 0
(-7250 1550);
DISPLAY 1.021277 (-7250 1550);
DISPLAY INVISIBLE (-7250 1550);
FORCEPROP 1 LASTPIN (-7300 1425) $PN 1
J 0
(-7295 1387);
DISPLAY 0.489362 (-7295 1387);
FORCEPROP 1 LASTPIN (-7300 1225) $PN 2
J 0
(-7295 1235);
DISPLAY 0.489362 (-7295 1235);
FORCEPROP 1 LAST WATTAGE 1/16W
J 0
(-7275 1275);
DISPLAY 0.489362 (-7275 1275);
PAINT SKYBLUE (-7275 1275);
FORCEPROP 1 LAST MATERIAL CHIP
J 0
(-7275 1225);
DISPLAY 0.489362 (-7275 1225);
PAINT SKYBLUE (-7275 1225);
FORCEPROP 1 LAST TOLERANCE 5%
J 0
(-7275 1325);
DISPLAY 0.489362 (-7275 1325);
PAINT SKYBLUE (-7275 1325);
FORCEPROP 1 LAST VALUE 1K
J 0
(-7275 1375);
DISPLAY 0.489362 (-7275 1375);
PAINT SKYBLUE (-7275 1375);
FORCEPROP 1 LAST PACK_TYPE 0402LF
J 0
(-7275 1175);
DISPLAY 0.489362 (-7275 1175);
PAINT SKYBLUE (-7275 1175);
FORCEPROP 2 LAST CDS_LIB pure_quanta
J 0
(-7300 1325);
DISPLAY INVISIBLE (-7300 1325);
FORCEPROP 1 LAST PATH I314
J 0
(-7250 1500);
DISPLAY 0.978723 (-7250 1500);
PAINT WHITE (-7250 1500);
DISPLAY INVISIBLE (-7250 1500);
FORCEPROP 1 LAST PART_NUMBER TMP_QCS21002JB34
J 0
(-7260 1200);
DISPLAY 0.617021 (-7260 1200);
PAINT SKYBLUE (-7260 1200);
DISPLAY INVISIBLE (-7260 1200);
FORCEADD Q_CAP..1
(-7300 625);
FORCEPROP 1 LAST LOCATION C233
J 0
(-7250 725);
DISPLAY 0.489362 (-7250 725);
PAINT SKYBLUE (-7250 725);
FORCEPROP 0 LAST $SEC 1
J 0
(-7250 775);
PAINT MONO (-7250 775);
DISPLAY INVISIBLE (-7250 775);
FORCEPROP 0 LAST CDS_SEC 1
J 0
(-7250 775);
PAINT MONO (-7250 775);
DISPLAY INVISIBLE (-7250 775);
FORCEPROP 1 LASTPIN (-7300 725) $PN 1
J 0
(-7290 705);
DISPLAY 0.489362 (-7290 705);
PAINT GREEN (-7290 705);
FORCEPROP 1 LASTPIN (-7300 525) $PN 2
J 0
(-7290 505);
DISPLAY 0.489362 (-7290 505);
PAINT GREEN (-7290 505);
FORCEPROP 1 LAST MATERIAL EMPTY
J 0
(-7250 425);
DISPLAY 0.489362 (-7250 425);
PAINT RED (-7250 425);
FORCEPROP 1 LAST TOLERANCE 10%
J 0
(-7250 575);
DISPLAY 0.489362 (-7250 575);
PAINT SKYBLUE (-7250 575);
FORCEPROP 1 LAST VALUE 0.001UF
J 0
(-7250 675);
DISPLAY 0.489362 (-7250 675);
PAINT SKYBLUE (-7250 675);
FORCEPROP 1 LAST VOLTAGE 50V
J 0
(-7250 625);
DISPLAY 0.489362 (-7250 625);
PAINT SKYBLUE (-7250 625);
FORCEPROP 1 LAST PACK_TYPE C0402
J 0
(-7250 475);
DISPLAY 0.489362 (-7250 475);
PAINT SKYBLUE (-7250 475);
FORCEPROP 2 LAST CDS_LIB pure_quanta
J 0
(-7300 625);
PAINT MONO (-7300 625);
DISPLAY INVISIBLE (-7300 625);
FORCEPROP 1 LAST PATH I315
J 0
(-7250 775);
DISPLAY 0.978723 (-7250 775);
PAINT WHITE (-7250 775);
DISPLAY INVISIBLE (-7250 775);
FORCEPROP 1 LAST PART_NUMBER CH30106KB19
J 0
(-7250 525);
DISPLAY 0.808511 (-7250 525);
PAINT SKYBLUE (-7250 525);
DISPLAY INVISIBLE (-7250 525);
FORCEADD Q_RES..2
(-7625 1325);
FORCEPROP 1 LAST LOCATION R525
J 0
(-7600 1425);
DISPLAY 0.489362 (-7600 1425);
PAINT SKYBLUE (-7600 1425);
FORCEPROP 2 LAST $SEC 1
J 0
(-7575 1550);
DISPLAY 0.680851 (-7575 1550);
PAINT MONO (-7575 1550);
DISPLAY INVISIBLE (-7575 1550);
FORCEPROP 2 LAST CDS_SEC 1
J 0
(-7575 1550);
DISPLAY 1.021277 (-7575 1550);
DISPLAY INVISIBLE (-7575 1550);
FORCEPROP 1 LASTPIN (-7625 1425) $PN 1
J 0
(-7620 1387);
DISPLAY 0.489362 (-7620 1387);
FORCEPROP 1 LASTPIN (-7625 1225) $PN 2
J 0
(-7620 1235);
DISPLAY 0.489362 (-7620 1235);
FORCEPROP 1 LAST WATTAGE 1/16W
J 0
(-7600 1275);
DISPLAY 0.489362 (-7600 1275);
PAINT SKYBLUE (-7600 1275);
FORCEPROP 1 LAST MATERIAL CHIP
J 0
(-7600 1225);
DISPLAY 0.489362 (-7600 1225);
PAINT SKYBLUE (-7600 1225);
FORCEPROP 1 LAST TOLERANCE 5%
J 0
(-7600 1325);
DISPLAY 0.489362 (-7600 1325);
PAINT SKYBLUE (-7600 1325);
FORCEPROP 1 LAST VALUE 1K
J 0
(-7600 1375);
DISPLAY 0.489362 (-7600 1375);
PAINT SKYBLUE (-7600 1375);
FORCEPROP 1 LAST PACK_TYPE 0402LF
J 0
(-7600 1175);
DISPLAY 0.489362 (-7600 1175);
PAINT SKYBLUE (-7600 1175);
FORCEPROP 2 LAST CDS_LIB pure_quanta
J 0
(-7625 1325);
DISPLAY INVISIBLE (-7625 1325);
FORCEPROP 1 LAST PATH I316
J 0
(-7575 1500);
DISPLAY 0.978723 (-7575 1500);
PAINT WHITE (-7575 1500);
DISPLAY INVISIBLE (-7575 1500);
FORCEPROP 1 LAST PART_NUMBER TMP_QCS21002JB34
J 0
(-7585 1200);
DISPLAY 0.617021 (-7585 1200);
PAINT SKYBLUE (-7585 1200);
DISPLAY INVISIBLE (-7585 1200);
FORCEADD Q_RES..2
(-7950 1325);
FORCEPROP 1 LAST LOCATION R524
J 0
(-7925 1425);
DISPLAY 0.489362 (-7925 1425);
PAINT SKYBLUE (-7925 1425);
FORCEPROP 2 LAST $SEC 1
J 0
(-7900 1550);
DISPLAY 0.680851 (-7900 1550);
PAINT MONO (-7900 1550);
DISPLAY INVISIBLE (-7900 1550);
FORCEPROP 2 LAST CDS_SEC 1
J 0
(-7900 1550);
DISPLAY 1.021277 (-7900 1550);
DISPLAY INVISIBLE (-7900 1550);
FORCEPROP 1 LASTPIN (-7950 1425) $PN 1
J 0
(-7945 1387);
DISPLAY 0.489362 (-7945 1387);
FORCEPROP 1 LASTPIN (-7950 1225) $PN 2
J 0
(-7945 1235);
DISPLAY 0.489362 (-7945 1235);
FORCEPROP 1 LAST WATTAGE 1/16W
J 0
(-7925 1275);
DISPLAY 0.489362 (-7925 1275);
PAINT SKYBLUE (-7925 1275);
FORCEPROP 1 LAST MATERIAL CHIP
J 0
(-7925 1225);
DISPLAY 0.489362 (-7925 1225);
PAINT SKYBLUE (-7925 1225);
FORCEPROP 1 LAST TOLERANCE 5%
J 0
(-7925 1325);
DISPLAY 0.489362 (-7925 1325);
PAINT SKYBLUE (-7925 1325);
FORCEPROP 1 LAST VALUE 1K
J 0
(-7925 1375);
DISPLAY 0.489362 (-7925 1375);
PAINT SKYBLUE (-7925 1375);
FORCEPROP 1 LAST PACK_TYPE 0402LF
J 0
(-7925 1175);
DISPLAY 0.489362 (-7925 1175);
PAINT SKYBLUE (-7925 1175);
FORCEPROP 2 LAST CDS_LIB pure_quanta
J 0
(-7950 1325);
DISPLAY INVISIBLE (-7950 1325);
FORCEPROP 1 LAST PATH I317
J 0
(-7900 1500);
DISPLAY 0.978723 (-7900 1500);
PAINT WHITE (-7900 1500);
DISPLAY INVISIBLE (-7900 1500);
FORCEPROP 1 LAST PART_NUMBER TMP_QCS21002JB34
J 0
(-7910 1200);
DISPLAY 0.617021 (-7910 1200);
PAINT SKYBLUE (-7910 1200);
DISPLAY INVISIBLE (-7910 1200);
FORCEADD Q_CAP..1
(-7625 625);
FORCEPROP 1 LAST LOCATION C232
J 0
(-7575 725);
DISPLAY 0.489362 (-7575 725);
PAINT SKYBLUE (-7575 725);
FORCEPROP 0 LAST $SEC 1
J 0
(-7575 775);
PAINT MONO (-7575 775);
DISPLAY INVISIBLE (-7575 775);
FORCEPROP 0 LAST CDS_SEC 1
J 0
(-7575 775);
PAINT MONO (-7575 775);
DISPLAY INVISIBLE (-7575 775);
FORCEPROP 1 LASTPIN (-7625 725) $PN 1
J 0
(-7615 705);
DISPLAY 0.489362 (-7615 705);
PAINT GREEN (-7615 705);
FORCEPROP 1 LASTPIN (-7625 525) $PN 2
J 0
(-7615 505);
DISPLAY 0.489362 (-7615 505);
PAINT GREEN (-7615 505);
FORCEPROP 1 LAST MATERIAL EMPTY
J 0
(-7575 425);
DISPLAY 0.489362 (-7575 425);
PAINT RED (-7575 425);
FORCEPROP 1 LAST TOLERANCE 10%
J 0
(-7575 575);
DISPLAY 0.489362 (-7575 575);
PAINT SKYBLUE (-7575 575);
FORCEPROP 1 LAST VALUE 0.001UF
J 0
(-7575 675);
DISPLAY 0.489362 (-7575 675);
PAINT SKYBLUE (-7575 675);
FORCEPROP 1 LAST VOLTAGE 50V
J 0
(-7575 625);
DISPLAY 0.489362 (-7575 625);
PAINT SKYBLUE (-7575 625);
FORCEPROP 1 LAST PACK_TYPE C0402
J 0
(-7575 475);
DISPLAY 0.489362 (-7575 475);
PAINT SKYBLUE (-7575 475);
FORCEPROP 2 LAST CDS_LIB pure_quanta
J 0
(-7625 625);
PAINT MONO (-7625 625);
DISPLAY INVISIBLE (-7625 625);
FORCEPROP 1 LAST PATH I318
J 0
(-7575 775);
DISPLAY 0.978723 (-7575 775);
PAINT WHITE (-7575 775);
DISPLAY INVISIBLE (-7575 775);
FORCEPROP 1 LAST PART_NUMBER CH30106KB19
J 0
(-7575 525);
DISPLAY 0.808511 (-7575 525);
PAINT SKYBLUE (-7575 525);
DISPLAY INVISIBLE (-7575 525);
FORCEADD Q_CAP..1
(-7950 625);
FORCEPROP 1 LAST LOCATION C231
J 0
(-7900 725);
DISPLAY 0.489362 (-7900 725);
PAINT SKYBLUE (-7900 725);
FORCEPROP 0 LAST $SEC 1
J 0
(-7900 775);
PAINT MONO (-7900 775);
DISPLAY INVISIBLE (-7900 775);
FORCEPROP 0 LAST CDS_SEC 1
J 0
(-7900 775);
PAINT MONO (-7900 775);
DISPLAY INVISIBLE (-7900 775);
FORCEPROP 1 LASTPIN (-7950 725) $PN 1
J 0
(-7940 705);
DISPLAY 0.489362 (-7940 705);
PAINT GREEN (-7940 705);
FORCEPROP 1 LASTPIN (-7950 525) $PN 2
J 0
(-7940 505);
DISPLAY 0.489362 (-7940 505);
PAINT GREEN (-7940 505);
FORCEPROP 1 LAST MATERIAL EMPTY
J 0
(-7900 425);
DISPLAY 0.489362 (-7900 425);
PAINT RED (-7900 425);
FORCEPROP 1 LAST TOLERANCE 10%
J 0
(-7900 575);
DISPLAY 0.489362 (-7900 575);
PAINT SKYBLUE (-7900 575);
FORCEPROP 1 LAST VALUE 0.001UF
J 0
(-7900 675);
DISPLAY 0.489362 (-7900 675);
PAINT SKYBLUE (-7900 675);
FORCEPROP 1 LAST VOLTAGE 50V
J 0
(-7900 625);
DISPLAY 0.489362 (-7900 625);
PAINT SKYBLUE (-7900 625);
FORCEPROP 1 LAST PACK_TYPE C0402
J 0
(-7900 475);
DISPLAY 0.489362 (-7900 475);
PAINT SKYBLUE (-7900 475);
FORCEPROP 2 LAST CDS_LIB pure_quanta
J 0
(-7950 625);
PAINT MONO (-7950 625);
DISPLAY INVISIBLE (-7950 625);
FORCEPROP 1 LAST PATH I319
J 0
(-7900 775);
DISPLAY 0.978723 (-7900 775);
PAINT WHITE (-7900 775);
DISPLAY INVISIBLE (-7900 775);
FORCEPROP 1 LAST PART_NUMBER CH30106KB19
J 0
(-7900 525);
DISPLAY 0.808511 (-7900 525);
PAINT SKYBLUE (-7900 525);
DISPLAY INVISIBLE (-7900 525);
FORCEADD GND..1
(-7300 325);
FORCEPROP 3 LASTPIN (-7300 375) SIG_NAME GND\g
J 0
(-7290 385);
DISPLAY 0.659574 (-7290 385);
PAINT MONO (-7290 385);
DISPLAY INVISIBLE (-7290 385);
FORCEPROP 1 LAST SIZE 1B
J 0
(-7225 275);
DISPLAY 0.872340 (-7225 275);
PAINT GREEN (-7225 275);
DISPLAY INVISIBLE (-7225 275);
FORCEPROP 2 LAST CDS_LIB pure_quanta_power
J 0
(-7300 325);
DISPLAY INVISIBLE (-7300 325);
FORCEPROP 1 LAST PATH I320
J 0
(-7225 325);
DISPLAY 0.872340 (-7225 325);
PAINT AQUA (-7225 325);
DISPLAY INVISIBLE (-7225 325);
FORCEPROP 1 LAST HDL_POWER GND
J 0
(-7300 475);
DISPLAY 0.872340 (-7300 475);
PAINT GREEN (-7300 475);
DISPLAY INVISIBLE (-7300 475);
FORCEADD GND..1
(-7625 325);
FORCEPROP 3 LASTPIN (-7625 375) SIG_NAME GND\g
J 0
(-7615 385);
DISPLAY 0.659574 (-7615 385);
PAINT MONO (-7615 385);
DISPLAY INVISIBLE (-7615 385);
FORCEPROP 1 LAST SIZE 1B
J 0
(-7550 275);
DISPLAY 0.872340 (-7550 275);
PAINT GREEN (-7550 275);
DISPLAY INVISIBLE (-7550 275);
FORCEPROP 2 LAST CDS_LIB pure_quanta_power
J 0
(-7625 325);
DISPLAY INVISIBLE (-7625 325);
FORCEPROP 1 LAST PATH I321
J 0
(-7550 325);
DISPLAY 0.872340 (-7550 325);
PAINT AQUA (-7550 325);
DISPLAY INVISIBLE (-7550 325);
FORCEPROP 1 LAST HDL_POWER GND
J 0
(-7625 475);
DISPLAY 0.872340 (-7625 475);
PAINT GREEN (-7625 475);
DISPLAY INVISIBLE (-7625 475);
FORCEADD GND..1
(-7950 325);
FORCEPROP 3 LASTPIN (-7950 375) SIG_NAME GND\g
J 0
(-7940 385);
DISPLAY 0.659574 (-7940 385);
PAINT MONO (-7940 385);
DISPLAY INVISIBLE (-7940 385);
FORCEPROP 2 LAST CDS_LIB pure_quanta_power
J 0
(-7950 325);
DISPLAY INVISIBLE (-7950 325);
FORCEPROP 1 LAST SIZE 1B
J 0
(-7875 275);
DISPLAY 0.872340 (-7875 275);
PAINT GREEN (-7875 275);
DISPLAY INVISIBLE (-7875 275);
FORCEPROP 1 LAST PATH I322
J 0
(-7875 325);
DISPLAY 0.872340 (-7875 325);
PAINT AQUA (-7875 325);
DISPLAY INVISIBLE (-7875 325);
FORCEPROP 1 LAST HDL_POWER GND
J 0
(-7950 475);
DISPLAY 0.872340 (-7950 475);
PAINT GREEN (-7950 475);
DISPLAY INVISIBLE (-7950 475);
FORCEADD UNIVERSAL_POWER..1
(-8275 1600);
FORCEPROP 3 LASTPIN (-8275 1550) SIG_NAME PVDD18_S5_P1\g
J 0
(-8265 1560);
DISPLAY 0.659574 (-8265 1560);
PAINT MONO (-8265 1560);
DISPLAY INVISIBLE (-8265 1560);
FORCEPROP 1 LAST HDL_POWER PVDD18_S5_P1
J 1
(-8275 1650);
DISPLAY 0.489362 (-8275 1650);
PAINT GREEN (-8275 1650);
FORCEPROP 2 LAST CDS_LIB pure_quanta_power
J 0
(-8275 1600);
DISPLAY INVISIBLE (-8275 1600);
FORCEPROP 1 LAST PATH I323
J 0
(-8225 1625);
DISPLAY 0.872340 (-8225 1625);
PAINT AQUA (-8225 1625);
DISPLAY INVISIBLE (-8225 1625);
FORCEADD Q_RES..2
(-8275 1325);
FORCEPROP 1 LAST LOCATION R523
J 0
(-8250 1425);
DISPLAY 0.489362 (-8250 1425);
PAINT SKYBLUE (-8250 1425);
FORCEPROP 2 LAST $SEC 1
J 0
(-8225 1550);
DISPLAY 0.680851 (-8225 1550);
PAINT MONO (-8225 1550);
DISPLAY INVISIBLE (-8225 1550);
FORCEPROP 2 LAST CDS_SEC 1
J 0
(-8225 1550);
DISPLAY 1.021277 (-8225 1550);
DISPLAY INVISIBLE (-8225 1550);
FORCEPROP 1 LASTPIN (-8275 1425) $PN 1
J 0
(-8270 1387);
DISPLAY 0.489362 (-8270 1387);
FORCEPROP 1 LASTPIN (-8275 1225) $PN 2
J 0
(-8270 1235);
DISPLAY 0.489362 (-8270 1235);
FORCEPROP 1 LAST WATTAGE 1/16W
J 0
(-8250 1275);
DISPLAY 0.489362 (-8250 1275);
PAINT SKYBLUE (-8250 1275);
FORCEPROP 1 LAST MATERIAL CHIP
J 0
(-8250 1225);
DISPLAY 0.489362 (-8250 1225);
PAINT SKYBLUE (-8250 1225);
FORCEPROP 1 LAST TOLERANCE 5%
J 0
(-8250 1325);
DISPLAY 0.489362 (-8250 1325);
PAINT SKYBLUE (-8250 1325);
FORCEPROP 1 LAST VALUE 1K
J 0
(-8250 1375);
DISPLAY 0.489362 (-8250 1375);
PAINT SKYBLUE (-8250 1375);
FORCEPROP 1 LAST PACK_TYPE 0402LF
J 0
(-8250 1175);
DISPLAY 0.489362 (-8250 1175);
PAINT SKYBLUE (-8250 1175);
FORCEPROP 2 LAST CDS_LIB pure_quanta
J 0
(-8275 1325);
DISPLAY INVISIBLE (-8275 1325);
FORCEPROP 1 LAST PATH I324
J 0
(-8225 1500);
DISPLAY 0.978723 (-8225 1500);
PAINT WHITE (-8225 1500);
DISPLAY INVISIBLE (-8225 1500);
FORCEPROP 1 LAST PART_NUMBER TMP_QCS21002JB34
J 0
(-8235 1200);
DISPLAY 0.617021 (-8235 1200);
PAINT SKYBLUE (-8235 1200);
DISPLAY INVISIBLE (-8235 1200);
FORCEADD Q_CAP..1
(-8275 625);
FORCEPROP 1 LAST LOCATION C230
J 0
(-8225 725);
DISPLAY 0.489362 (-8225 725);
PAINT SKYBLUE (-8225 725);
FORCEPROP 0 LAST $SEC 1
J 0
(-8225 775);
PAINT MONO (-8225 775);
DISPLAY INVISIBLE (-8225 775);
FORCEPROP 0 LAST CDS_SEC 1
J 0
(-8225 775);
PAINT MONO (-8225 775);
DISPLAY INVISIBLE (-8225 775);
FORCEPROP 1 LASTPIN (-8275 725) $PN 1
J 0
(-8265 705);
DISPLAY 0.489362 (-8265 705);
PAINT GREEN (-8265 705);
FORCEPROP 1 LASTPIN (-8275 525) $PN 2
J 0
(-8265 505);
DISPLAY 0.489362 (-8265 505);
PAINT GREEN (-8265 505);
FORCEPROP 1 LAST MATERIAL EMPTY
J 0
(-8225 425);
DISPLAY 0.489362 (-8225 425);
PAINT RED (-8225 425);
FORCEPROP 1 LAST TOLERANCE 10%
J 0
(-8225 575);
DISPLAY 0.489362 (-8225 575);
PAINT SKYBLUE (-8225 575);
FORCEPROP 1 LAST VALUE 0.001UF
J 0
(-8225 675);
DISPLAY 0.489362 (-8225 675);
PAINT SKYBLUE (-8225 675);
FORCEPROP 1 LAST VOLTAGE 50V
J 0
(-8225 625);
DISPLAY 0.489362 (-8225 625);
PAINT SKYBLUE (-8225 625);
FORCEPROP 1 LAST PACK_TYPE C0402
J 0
(-8225 475);
DISPLAY 0.489362 (-8225 475);
PAINT SKYBLUE (-8225 475);
FORCEPROP 2 LAST CDS_LIB pure_quanta
J 0
(-8275 625);
PAINT MONO (-8275 625);
DISPLAY INVISIBLE (-8275 625);
FORCEPROP 1 LAST PATH I325
J 0
(-8225 775);
DISPLAY 0.978723 (-8225 775);
PAINT WHITE (-8225 775);
DISPLAY INVISIBLE (-8225 775);
FORCEPROP 1 LAST PART_NUMBER CH30106KB19
J 0
(-8225 525);
DISPLAY 0.808511 (-8225 525);
PAINT SKYBLUE (-8225 525);
DISPLAY INVISIBLE (-8225 525);
FORCEADD OFFPAGE..2
R 2
(-8900 1125);
FORCEPROP 2 LAST $XR1 151 
J 0
(-9244 1125);
DISPLAY 0.638298 (-9244 1125);
PAINT MONO (-9244 1125);
FORCEPROP 2 LAST $XR0 54 
J 0
(-9124 1125);
DISPLAY 0.638298 (-9124 1125);
PAINT MONO (-9124 1125);
FORCEPROP 2 LAST PATH I326
J 0
(-9100 1175);
DISPLAY 0.680851 (-9100 1175);
DISPLAY INVISIBLE (-9100 1175);
FORCEPROP 1 LAST COMMENT_BODY TRUE
J 2
(-8855 1030);
DISPLAY 0.872340 (-8855 1030);
PAINT GREEN (-8855 1030);
DISPLAY INVISIBLE (-8855 1030);
FORCEPROP 1 LAST OFFPAGE TRUE
J 2
(-9225 1000);
DISPLAY 0.872340 (-9225 1000);
PAINT GREEN (-9225 1000);
DISPLAY INVISIBLE (-9225 1000);
FORCEPROP 2 LAST CDS_LIB standard
J 2
(-8900 1125);
DISPLAY INVISIBLE (-8900 1125);
FORCEADD OFFPAGE..2
R 2
(-8900 1025);
FORCEPROP 2 LAST $XR1 54 
J 0
(-9245 1025);
DISPLAY 0.638298 (-9245 1025);
PAINT MONO (-9245 1025);
FORCEPROP 2 LAST $XR0 150 
J 0
(-9155 1025);
DISPLAY 0.638298 (-9155 1025);
PAINT MONO (-9155 1025);
FORCEPROP 2 LAST PATH I327
J 0
(-9150 1075);
DISPLAY 0.680851 (-9150 1075);
DISPLAY INVISIBLE (-9150 1075);
FORCEPROP 1 LAST COMMENT_BODY TRUE
J 2
(-8855 930);
DISPLAY 0.872340 (-8855 930);
PAINT GREEN (-8855 930);
DISPLAY INVISIBLE (-8855 930);
FORCEPROP 1 LAST OFFPAGE TRUE
J 2
(-9225 900);
DISPLAY 0.872340 (-9225 900);
PAINT GREEN (-9225 900);
DISPLAY INVISIBLE (-9225 900);
FORCEPROP 2 LAST CDS_LIB standard
J 0
(-8900 1025);
DISPLAY INVISIBLE (-8900 1025);
FORCEADD OFFPAGE..2
R 2
(-8900 1075);
FORCEPROP 2 LAST $XR1 54 
J 0
(-9245 1075);
DISPLAY 0.638298 (-9245 1075);
PAINT MONO (-9245 1075);
FORCEPROP 2 LAST $XR0 151 
J 0
(-9155 1075);
DISPLAY 0.638298 (-9155 1075);
PAINT MONO (-9155 1075);
FORCEPROP 2 LAST PATH I328
J 0
(-9150 1125);
DISPLAY 0.680851 (-9150 1125);
DISPLAY INVISIBLE (-9150 1125);
FORCEPROP 1 LAST COMMENT_BODY TRUE
J 2
(-8855 980);
DISPLAY 0.872340 (-8855 980);
PAINT GREEN (-8855 980);
DISPLAY INVISIBLE (-8855 980);
FORCEPROP 1 LAST OFFPAGE TRUE
J 2
(-9225 950);
DISPLAY 0.872340 (-9225 950);
PAINT GREEN (-9225 950);
DISPLAY INVISIBLE (-9225 950);
FORCEPROP 2 LAST CDS_LIB standard
J 0
(-8900 1075);
DISPLAY INVISIBLE (-8900 1075);
FORCEADD OFFPAGE..2
R 2
(-8900 975);
FORCEPROP 2 LAST $XR1 54 
J 0
(-9245 975);
DISPLAY 0.638298 (-9245 975);
PAINT MONO (-9245 975);
FORCEPROP 2 LAST $XR0 150 
J 0
(-9155 975);
DISPLAY 0.638298 (-9155 975);
PAINT MONO (-9155 975);
FORCEPROP 2 LAST PATH I329
J 0
(-9150 1025);
DISPLAY 0.680851 (-9150 1025);
DISPLAY INVISIBLE (-9150 1025);
FORCEPROP 1 LAST COMMENT_BODY TRUE
J 2
(-8855 880);
DISPLAY 0.872340 (-8855 880);
PAINT GREEN (-8855 880);
DISPLAY INVISIBLE (-8855 880);
FORCEPROP 1 LAST OFFPAGE TRUE
J 2
(-9225 850);
DISPLAY 0.872340 (-9225 850);
PAINT GREEN (-9225 850);
DISPLAY INVISIBLE (-9225 850);
FORCEPROP 2 LAST CDS_LIB standard
J 0
(-8900 975);
DISPLAY INVISIBLE (-8900 975);
FORCEADD OFFPAGE..2
R 2
(-8900 925);
FORCEPROP 2 LAST $XR1 54 
J 0
(-9245 925);
DISPLAY 0.638298 (-9245 925);
PAINT MONO (-9245 925);
FORCEPROP 2 LAST $XR0 150 
J 0
(-9155 925);
DISPLAY 0.638298 (-9155 925);
PAINT MONO (-9155 925);
FORCEPROP 2 LAST PATH I330
J 0
(-9150 975);
DISPLAY 0.680851 (-9150 975);
DISPLAY INVISIBLE (-9150 975);
FORCEPROP 1 LAST COMMENT_BODY TRUE
J 2
(-8855 830);
DISPLAY 0.872340 (-8855 830);
PAINT GREEN (-8855 830);
DISPLAY INVISIBLE (-8855 830);
FORCEPROP 1 LAST OFFPAGE TRUE
J 2
(-9225 800);
DISPLAY 0.872340 (-9225 800);
PAINT GREEN (-9225 800);
DISPLAY INVISIBLE (-9225 800);
FORCEPROP 2 LAST CDS_LIB standard
J 0
(-8900 925);
DISPLAY INVISIBLE (-8900 925);
FORCEADD OFFPAGE..2
R 2
(-8900 875);
FORCEPROP 2 LAST $XR1 54 
J 0
(-9245 875);
DISPLAY 0.638298 (-9245 875);
PAINT MONO (-9245 875);
FORCEPROP 2 LAST $XR0 150 
J 0
(-9155 875);
DISPLAY 0.638298 (-9155 875);
PAINT MONO (-9155 875);
FORCEPROP 2 LAST PATH I331
J 0
(-9150 925);
DISPLAY 0.680851 (-9150 925);
DISPLAY INVISIBLE (-9150 925);
FORCEPROP 1 LAST COMMENT_BODY TRUE
J 2
(-8855 780);
DISPLAY 0.872340 (-8855 780);
PAINT GREEN (-8855 780);
DISPLAY INVISIBLE (-8855 780);
FORCEPROP 1 LAST OFFPAGE TRUE
J 2
(-9225 750);
DISPLAY 0.872340 (-9225 750);
PAINT GREEN (-9225 750);
DISPLAY INVISIBLE (-9225 750);
FORCEPROP 2 LAST CDS_LIB standard
J 0
(-8900 875);
DISPLAY INVISIBLE (-8900 875);
FORCEADD GND..1
(-8275 325);
FORCEPROP 3 LASTPIN (-8275 375) SIG_NAME GND\g
J 0
(-8265 385);
DISPLAY 0.659574 (-8265 385);
PAINT MONO (-8265 385);
DISPLAY INVISIBLE (-8265 385);
FORCEPROP 2 LAST CDS_LIB pure_quanta_power
J 0
(-8275 325);
DISPLAY INVISIBLE (-8275 325);
FORCEPROP 1 LAST SIZE 1B
J 0
(-8200 275);
DISPLAY 0.872340 (-8200 275);
PAINT GREEN (-8200 275);
DISPLAY INVISIBLE (-8200 275);
FORCEPROP 1 LAST PATH I332
J 0
(-8200 325);
DISPLAY 0.872340 (-8200 325);
PAINT AQUA (-8200 325);
DISPLAY INVISIBLE (-8200 325);
FORCEPROP 1 LAST HDL_POWER GND
J 0
(-8275 475);
DISPLAY 0.872340 (-8275 475);
PAINT GREEN (-8275 475);
DISPLAY INVISIBLE (-8275 475);
FORCEADD Q_RES..1
(-6775 5725);
FORCEPROP 1 LAST LOCATION PR170
J 0
(-7000 5725);
DISPLAY 0.489362 (-7000 5725);
PAINT SKYBLUE (-7000 5725);
FORCEPROP 0 LAST $SEC 1
J 0
(-6825 5800);
DISPLAY 0.680851 (-6825 5800);
PAINT MONO (-6825 5800);
DISPLAY INVISIBLE (-6825 5800);
FORCEPROP 0 LAST CDS_SEC 1
J 0
(-6825 5800);
DISPLAY 1.021277 (-6825 5800);
DISPLAY INVISIBLE (-6825 5800);
FORCEPROP 1 LASTPIN (-6875 5725) $PN 1
J 0
(-6863 5737);
DISPLAY 0.489362 (-6863 5737);
PAINT MONO (-6863 5737);
FORCEPROP 1 LASTPIN (-6675 5725) $PN 2
J 0
(-6713 5737);
DISPLAY 0.489362 (-6713 5737);
PAINT MONO (-6713 5737);
FORCEPROP 1 LAST VALUE 0
J 2
(-6600 5725);
DISPLAY 0.489362 (-6600 5725);
PAINT SKYBLUE (-6600 5725);
FORCEPROP 2 LAST CDS_LIB pure_quanta
J 0
(-6775 5725);
DISPLAY INVISIBLE (-6775 5725);
FORCEPROP 1 LAST PATH I333
J 0
(-6825 5875);
DISPLAY 0.978723 (-6825 5875);
PAINT WHITE (-6825 5875);
DISPLAY INVISIBLE (-6825 5875);
FORCEPROP 1 LAST WATTAGE 1/16W
J 0
(-6675 5675);
DISPLAY 0.489362 (-6675 5675);
PAINT SKYBLUE (-6675 5675);
DISPLAY INVISIBLE (-6675 5675);
FORCEPROP 1 LAST MATERIAL CHIP
J 0
(-7025 5650);
DISPLAY 0.489362 (-7025 5650);
PAINT SKYBLUE (-7025 5650);
DISPLAY INVISIBLE (-7025 5650);
FORCEPROP 1 LAST TOLERANCE 5%
J 0
(-6650 5750);
DISPLAY 0.489362 (-6650 5750);
PAINT SKYBLUE (-6650 5750);
DISPLAY INVISIBLE (-6650 5750);
FORCEPROP 1 LAST PART_NUMBER CS00002JB38
J 0
(-7025 5675);
DISPLAY 0.489362 (-7025 5675);
PAINT SKYBLUE (-7025 5675);
DISPLAY INVISIBLE (-7025 5675);
FORCEPROP 1 LAST PACK_TYPE 0402LF
J 0
(-6675 5650);
DISPLAY 0.489362 (-6675 5650);
PAINT SKYBLUE (-6675 5650);
DISPLAY INVISIBLE (-6675 5650);
FORCEADD Q_RES..1
(-6775 5775);
FORCEPROP 1 LAST LOCATION PR169
J 0
(-7000 5775);
DISPLAY 0.489362 (-7000 5775);
PAINT SKYBLUE (-7000 5775);
FORCEPROP 0 LAST $SEC 1
J 0
(-6825 5850);
DISPLAY 0.680851 (-6825 5850);
PAINT MONO (-6825 5850);
DISPLAY INVISIBLE (-6825 5850);
FORCEPROP 0 LAST CDS_SEC 1
J 0
(-6825 5850);
DISPLAY 1.021277 (-6825 5850);
DISPLAY INVISIBLE (-6825 5850);
FORCEPROP 1 LASTPIN (-6875 5775) $PN 1
J 0
(-6863 5787);
DISPLAY 0.489362 (-6863 5787);
PAINT MONO (-6863 5787);
FORCEPROP 1 LASTPIN (-6675 5775) $PN 2
J 0
(-6713 5787);
DISPLAY 0.489362 (-6713 5787);
PAINT MONO (-6713 5787);
FORCEPROP 1 LAST VALUE 0
J 2
(-6600 5775);
DISPLAY 0.489362 (-6600 5775);
PAINT SKYBLUE (-6600 5775);
FORCEPROP 2 LAST CDS_LIB pure_quanta
J 0
(-6775 5775);
DISPLAY INVISIBLE (-6775 5775);
FORCEPROP 1 LAST PATH I334
J 0
(-6825 5925);
DISPLAY 0.978723 (-6825 5925);
PAINT WHITE (-6825 5925);
DISPLAY INVISIBLE (-6825 5925);
FORCEPROP 1 LAST WATTAGE 1/16W
J 0
(-6675 5725);
DISPLAY 0.489362 (-6675 5725);
PAINT SKYBLUE (-6675 5725);
DISPLAY INVISIBLE (-6675 5725);
FORCEPROP 1 LAST MATERIAL CHIP
J 0
(-7025 5700);
DISPLAY 0.489362 (-7025 5700);
PAINT SKYBLUE (-7025 5700);
DISPLAY INVISIBLE (-7025 5700);
FORCEPROP 1 LAST TOLERANCE 5%
J 0
(-6650 5800);
DISPLAY 0.489362 (-6650 5800);
PAINT SKYBLUE (-6650 5800);
DISPLAY INVISIBLE (-6650 5800);
FORCEPROP 1 LAST PART_NUMBER CS00002JB38
J 0
(-7025 5725);
DISPLAY 0.489362 (-7025 5725);
PAINT SKYBLUE (-7025 5725);
DISPLAY INVISIBLE (-7025 5725);
FORCEPROP 1 LAST PACK_TYPE 0402LF
J 0
(-6675 5700);
DISPLAY 0.489362 (-6675 5700);
PAINT SKYBLUE (-6675 5700);
DISPLAY INVISIBLE (-6675 5700);
FORCEADD OFFPAGE..2
R 2
(-7875 5725);
FORCEPROP 2 LAST $XR0 186 
J 0
(-8130 5725);
DISPLAY 0.638298 (-8130 5725);
PAINT MONO (-8130 5725);
FORCEPROP 2 LAST PATH I335
J 0
(-7825 5800);
DISPLAY 0.680851 (-7825 5800);
DISPLAY INVISIBLE (-7825 5800);
FORCEPROP 1 LAST COMMENT_BODY TRUE
J 2
(-7830 5630);
DISPLAY 0.872340 (-7830 5630);
PAINT GREEN (-7830 5630);
DISPLAY INVISIBLE (-7830 5630);
FORCEPROP 1 LAST OFFPAGE TRUE
J 2
(-8200 5600);
DISPLAY 0.872340 (-8200 5600);
PAINT GREEN (-8200 5600);
DISPLAY INVISIBLE (-8200 5600);
FORCEPROP 2 LAST CDS_LIB standard
J 0
(-7875 5725);
DISPLAY INVISIBLE (-7875 5725);
FORCEADD OFFPAGE..2
R 2
(-7875 5775);
FORCEPROP 2 LAST $XR0 186 
J 0
(-8130 5775);
DISPLAY 0.638298 (-8130 5775);
PAINT MONO (-8130 5775);
FORCEPROP 2 LAST PATH I336
J 0
(-7825 5850);
DISPLAY 0.680851 (-7825 5850);
DISPLAY INVISIBLE (-7825 5850);
FORCEPROP 1 LAST COMMENT_BODY TRUE
J 2
(-7830 5680);
DISPLAY 0.872340 (-7830 5680);
PAINT GREEN (-7830 5680);
DISPLAY INVISIBLE (-7830 5680);
FORCEPROP 1 LAST OFFPAGE TRUE
J 2
(-8200 5650);
DISPLAY 0.872340 (-8200 5650);
PAINT GREEN (-8200 5650);
DISPLAY INVISIBLE (-8200 5650);
FORCEPROP 2 LAST CDS_LIB standard
J 0
(-7875 5775);
DISPLAY INVISIBLE (-7875 5775);
FORCEADD Q_RES..1
(-6775 5525);
FORCEPROP 1 LAST LOCATION PR237
J 0
(-7000 5525);
DISPLAY 0.489362 (-7000 5525);
PAINT SKYBLUE (-7000 5525);
FORCEPROP 0 LAST $SEC 1
J 0
(-6825 5625);
DISPLAY 0.680851 (-6825 5625);
PAINT MONO (-6825 5625);
DISPLAY INVISIBLE (-6825 5625);
FORCEPROP 0 LAST CDS_SEC 1
J 0
(-6825 5625);
DISPLAY 1.021277 (-6825 5625);
DISPLAY INVISIBLE (-6825 5625);
FORCEPROP 1 LASTPIN (-6875 5525) $PN 1
J 0
(-6863 5537);
DISPLAY 0.489362 (-6863 5537);
PAINT MONO (-6863 5537);
FORCEPROP 1 LASTPIN (-6675 5525) $PN 2
J 0
(-6713 5537);
DISPLAY 0.489362 (-6713 5537);
PAINT MONO (-6713 5537);
FORCEPROP 1 LAST VALUE 0
J 2
(-6600 5525);
DISPLAY 0.489362 (-6600 5525);
PAINT SKYBLUE (-6600 5525);
FORCEPROP 2 LAST CDS_LIB pure_quanta
J 0
(-6775 5525);
DISPLAY INVISIBLE (-6775 5525);
FORCEPROP 1 LAST PATH I337
J 0
(-6825 5675);
DISPLAY 0.978723 (-6825 5675);
PAINT WHITE (-6825 5675);
DISPLAY INVISIBLE (-6825 5675);
FORCEPROP 1 LAST WATTAGE 1/16W
J 2
(-6375 5625);
DISPLAY 0.489362 (-6375 5625);
PAINT SKYBLUE (-6375 5625);
DISPLAY INVISIBLE (-6375 5625);
FORCEPROP 1 LAST MATERIAL CHIP
J 0
(-6650 5625);
DISPLAY 0.489362 (-6650 5625);
PAINT SKYBLUE (-6650 5625);
DISPLAY INVISIBLE (-6650 5625);
FORCEPROP 1 LAST TOLERANCE 5%
J 0
(-6250 5575);
DISPLAY 0.489362 (-6250 5575);
PAINT SKYBLUE (-6250 5575);
DISPLAY INVISIBLE (-6250 5575);
FORCEPROP 1 LAST PART_NUMBER CS00002JB38
J 0
(-6650 5575);
DISPLAY 0.489362 (-6650 5575);
PAINT SKYBLUE (-6650 5575);
DISPLAY INVISIBLE (-6650 5575);
FORCEPROP 1 LAST PACK_TYPE 0402LF
J 0
(-6175 5575);
DISPLAY 0.489362 (-6175 5575);
PAINT SKYBLUE (-6175 5575);
DISPLAY INVISIBLE (-6175 5575);
FORCEADD Q_RES..1
(-6775 5575);
FORCEPROP 1 LAST LOCATION PR236
J 0
(-7000 5575);
DISPLAY 0.489362 (-7000 5575);
PAINT SKYBLUE (-7000 5575);
FORCEPROP 0 LAST $SEC 1
J 0
(-6375 5700);
DISPLAY 0.680851 (-6375 5700);
PAINT MONO (-6375 5700);
DISPLAY INVISIBLE (-6375 5700);
FORCEPROP 0 LAST CDS_SEC 1
J 0
(-6375 5700);
DISPLAY 1.021277 (-6375 5700);
DISPLAY INVISIBLE (-6375 5700);
FORCEPROP 1 LASTPIN (-6875 5575) $PN 1
J 0
(-6863 5587);
DISPLAY 0.489362 (-6863 5587);
PAINT MONO (-6863 5587);
FORCEPROP 1 LASTPIN (-6675 5575) $PN 2
J 0
(-6713 5587);
DISPLAY 0.489362 (-6713 5587);
PAINT MONO (-6713 5587);
FORCEPROP 1 LAST VALUE 0
J 2
(-6600 5575);
DISPLAY 0.489362 (-6600 5575);
PAINT SKYBLUE (-6600 5575);
FORCEPROP 2 LAST CDS_LIB pure_quanta
J 0
(-6775 5575);
DISPLAY INVISIBLE (-6775 5575);
FORCEPROP 1 LAST PATH I338
J 0
(-6825 5725);
DISPLAY 0.978723 (-6825 5725);
PAINT WHITE (-6825 5725);
DISPLAY INVISIBLE (-6825 5725);
FORCEPROP 1 LAST WATTAGE 1/16W
J 2
(-6375 5675);
DISPLAY 0.489362 (-6375 5675);
PAINT SKYBLUE (-6375 5675);
DISPLAY INVISIBLE (-6375 5675);
FORCEPROP 1 LAST MATERIAL CHIP
J 0
(-6650 5675);
DISPLAY 0.489362 (-6650 5675);
PAINT SKYBLUE (-6650 5675);
DISPLAY INVISIBLE (-6650 5675);
FORCEPROP 1 LAST TOLERANCE 5%
J 0
(-6250 5625);
DISPLAY 0.489362 (-6250 5625);
PAINT SKYBLUE (-6250 5625);
DISPLAY INVISIBLE (-6250 5625);
FORCEPROP 1 LAST PART_NUMBER CS00002JB38
J 0
(-6650 5625);
DISPLAY 0.489362 (-6650 5625);
PAINT SKYBLUE (-6650 5625);
DISPLAY INVISIBLE (-6650 5625);
FORCEPROP 1 LAST PACK_TYPE 0402LF
J 0
(-6175 5625);
DISPLAY 0.489362 (-6175 5625);
PAINT SKYBLUE (-6175 5625);
DISPLAY INVISIBLE (-6175 5625);
FORCEADD OFFPAGE..2
R 2
(-7875 5525);
FORCEPROP 2 LAST $XR0 193 
J 0
(-8130 5525);
DISPLAY 0.638298 (-8130 5525);
PAINT MONO (-8130 5525);
FORCEPROP 2 LAST PATH I339
J 0
(-7825 5600);
DISPLAY 0.680851 (-7825 5600);
DISPLAY INVISIBLE (-7825 5600);
FORCEPROP 1 LAST COMMENT_BODY TRUE
J 2
(-7830 5430);
DISPLAY 0.872340 (-7830 5430);
PAINT GREEN (-7830 5430);
DISPLAY INVISIBLE (-7830 5430);
FORCEPROP 1 LAST OFFPAGE TRUE
J 2
(-8200 5400);
DISPLAY 0.872340 (-8200 5400);
PAINT GREEN (-8200 5400);
DISPLAY INVISIBLE (-8200 5400);
FORCEPROP 2 LAST CDS_LIB standard
J 0
(-7875 5525);
DISPLAY INVISIBLE (-7875 5525);
FORCEADD OFFPAGE..2
R 2
(-7875 5575);
FORCEPROP 2 LAST $XR0 193 
J 0
(-8130 5575);
DISPLAY 0.638298 (-8130 5575);
PAINT MONO (-8130 5575);
FORCEPROP 2 LAST PATH I340
J 0
(-7825 5650);
DISPLAY 0.680851 (-7825 5650);
DISPLAY INVISIBLE (-7825 5650);
FORCEPROP 1 LAST COMMENT_BODY TRUE
J 2
(-7830 5480);
DISPLAY 0.872340 (-7830 5480);
PAINT GREEN (-7830 5480);
DISPLAY INVISIBLE (-7830 5480);
FORCEPROP 1 LAST OFFPAGE TRUE
J 2
(-8200 5450);
DISPLAY 0.872340 (-8200 5450);
PAINT GREEN (-8200 5450);
DISPLAY INVISIBLE (-8200 5450);
FORCEPROP 2 LAST CDS_LIB standard
J 0
(-7875 5575);
DISPLAY INVISIBLE (-7875 5575);
FORCEADD OFFPAGE..3
(-2375 4775);
FORCEPROP 2 LAST $XR1 81 
J 0
(-2071 4775);
DISPLAY 0.638298 (-2071 4775);
PAINT MONO (-2071 4775);
FORCEPROP 2 LAST $XR0 54 
J 0
(-2161 4775);
DISPLAY 0.638298 (-2161 4775);
PAINT MONO (-2161 4775);
FORCEPROP 2 LAST PATH I357
J 0
(-2050 4825);
DISPLAY 0.680851 (-2050 4825);
DISPLAY INVISIBLE (-2050 4825);
FORCEPROP 1 LAST COMMENT_BODY TRUE
J 0
(-2425 4675);
DISPLAY 0.872340 (-2425 4675);
PAINT GREEN (-2425 4675);
DISPLAY INVISIBLE (-2425 4675);
FORCEPROP 1 LAST OFFPAGE TRUE
J 0
(-2050 4650);
DISPLAY 0.872340 (-2050 4650);
PAINT GREEN (-2050 4650);
DISPLAY INVISIBLE (-2050 4650);
FORCEPROP 2 LAST CDS_LIB standard
J 0
(-2375 4775);
DISPLAY INVISIBLE (-2375 4775);
FORCEADD OFFPAGE..3
(-2375 4725);
FORCEPROP 2 LAST $XR1 81 
J 0
(-2071 4725);
DISPLAY 0.638298 (-2071 4725);
PAINT MONO (-2071 4725);
FORCEPROP 2 LAST $XR0 54 
J 0
(-2161 4725);
DISPLAY 0.638298 (-2161 4725);
PAINT MONO (-2161 4725);
FORCEPROP 2 LAST PATH I358
J 0
(-2050 4775);
DISPLAY 0.680851 (-2050 4775);
DISPLAY INVISIBLE (-2050 4775);
FORCEPROP 1 LAST COMMENT_BODY TRUE
J 0
(-2425 4625);
DISPLAY 0.872340 (-2425 4625);
PAINT GREEN (-2425 4625);
DISPLAY INVISIBLE (-2425 4625);
FORCEPROP 1 LAST OFFPAGE TRUE
J 0
(-2050 4600);
DISPLAY 0.872340 (-2050 4600);
PAINT GREEN (-2050 4600);
DISPLAY INVISIBLE (-2050 4600);
FORCEPROP 2 LAST CDS_LIB standard
J 0
(-2375 4725);
DISPLAY INVISIBLE (-2375 4725);
FORCEADD OFFPAGE..3
(-2375 4825);
FORCEPROP 2 LAST $XR1 81 
J 0
(-2071 4825);
DISPLAY 0.638298 (-2071 4825);
PAINT MONO (-2071 4825);
FORCEPROP 2 LAST $XR0 54 
J 0
(-2161 4825);
DISPLAY 0.638298 (-2161 4825);
PAINT MONO (-2161 4825);
FORCEPROP 2 LAST PATH I359
J 0
(-2050 4875);
DISPLAY 0.680851 (-2050 4875);
DISPLAY INVISIBLE (-2050 4875);
FORCEPROP 1 LAST COMMENT_BODY TRUE
J 0
(-2425 4725);
DISPLAY 0.872340 (-2425 4725);
PAINT GREEN (-2425 4725);
DISPLAY INVISIBLE (-2425 4725);
FORCEPROP 1 LAST OFFPAGE TRUE
J 0
(-2050 4700);
DISPLAY 0.872340 (-2050 4700);
PAINT GREEN (-2050 4700);
DISPLAY INVISIBLE (-2050 4700);
FORCEPROP 2 LAST CDS_LIB standard
J 0
(-2375 4825);
DISPLAY INVISIBLE (-2375 4825);
FORCEADD OFFPAGE..3
(-2375 4675);
FORCEPROP 2 LAST $XR1 81 
J 0
(-2071 4675);
DISPLAY 0.638298 (-2071 4675);
PAINT MONO (-2071 4675);
FORCEPROP 2 LAST $XR0 54 
J 0
(-2161 4675);
DISPLAY 0.638298 (-2161 4675);
PAINT MONO (-2161 4675);
FORCEPROP 2 LAST PATH I360
J 0
(-2050 4725);
DISPLAY 0.680851 (-2050 4725);
DISPLAY INVISIBLE (-2050 4725);
FORCEPROP 1 LAST COMMENT_BODY TRUE
J 0
(-2425 4575);
DISPLAY 0.872340 (-2425 4575);
PAINT GREEN (-2425 4575);
DISPLAY INVISIBLE (-2425 4575);
FORCEPROP 1 LAST OFFPAGE TRUE
J 0
(-2050 4550);
DISPLAY 0.872340 (-2050 4550);
PAINT GREEN (-2050 4550);
DISPLAY INVISIBLE (-2050 4550);
FORCEPROP 2 LAST CDS_LIB standard
J 0
(-2375 4675);
DISPLAY INVISIBLE (-2375 4675);
FORCEADD Q_RES..1
(-3100 4775);
FORCEPROP 1 LAST LOCATION R618
J 0
(-2975 4775);
DISPLAY 0.489362 (-2975 4775);
PAINT SKYBLUE (-2975 4775);
FORCEPROP 0 LAST $SEC 1
J 0
(-2975 4825);
DISPLAY 0.680851 (-2975 4825);
PAINT MONO (-2975 4825);
DISPLAY INVISIBLE (-2975 4825);
FORCEPROP 0 LAST CDS_SEC 1
J 0
(-2975 4825);
DISPLAY 0.680851 (-2975 4825);
DISPLAY INVISIBLE (-2975 4825);
FORCEPROP 1 LASTPIN (-3200 4775) $PN 1
J 0
(-3188 4787);
DISPLAY 0.489362 (-3188 4787);
PAINT MONO (-3188 4787);
FORCEPROP 1 LASTPIN (-3000 4775) $PN 2
J 0
(-3038 4787);
DISPLAY 0.489362 (-3038 4787);
PAINT MONO (-3038 4787);
FORCEPROP 1 LAST VALUE 0
J 2
(-3200 4775);
DISPLAY 0.489362 (-3200 4775);
PAINT SKYBLUE (-3200 4775);
FORCEPROP 2 LAST CDS_LIB pure_quanta
J 0
(-3100 4775);
DISPLAY INVISIBLE (-3100 4775);
FORCEPROP 1 LAST PATH I361
J 0
(-3150 4925);
DISPLAY 0.978723 (-3150 4925);
PAINT WHITE (-3150 4925);
DISPLAY INVISIBLE (-3150 4925);
FORCEPROP 1 LAST WATTAGE 1/16W
J 2
(-2700 4700);
DISPLAY 0.489362 (-2700 4700);
PAINT SKYBLUE (-2700 4700);
DISPLAY INVISIBLE (-2700 4700);
FORCEPROP 1 LAST MATERIAL CHIP
J 0
(-2675 4700);
DISPLAY 0.489362 (-2675 4700);
PAINT SKYBLUE (-2675 4700);
DISPLAY INVISIBLE (-2675 4700);
FORCEPROP 1 LAST TOLERANCE 5%
J 0
(-3125 4700);
DISPLAY 0.489362 (-3125 4700);
PAINT SKYBLUE (-3125 4700);
DISPLAY INVISIBLE (-3125 4700);
FORCEPROP 1 LAST PART_NUMBER CS00002JB38
J 0
(-3075 4825);
DISPLAY 0.489362 (-3075 4825);
PAINT SKYBLUE (-3075 4825);
DISPLAY INVISIBLE (-3075 4825);
FORCEPROP 1 LAST PACK_TYPE 0402LF
J 0
(-3050 4700);
DISPLAY 0.489362 (-3050 4700);
PAINT SKYBLUE (-3050 4700);
DISPLAY INVISIBLE (-3050 4700);
FORCEADD Q_RES..1
(-3100 4825);
FORCEPROP 1 LAST LOCATION R486
J 0
(-2975 4825);
DISPLAY 0.489362 (-2975 4825);
PAINT SKYBLUE (-2975 4825);
FORCEPROP 0 LAST $SEC 1
J 0
(-2975 4875);
DISPLAY 0.680851 (-2975 4875);
PAINT MONO (-2975 4875);
DISPLAY INVISIBLE (-2975 4875);
FORCEPROP 0 LAST CDS_SEC 1
J 0
(-2975 4875);
DISPLAY 0.680851 (-2975 4875);
DISPLAY INVISIBLE (-2975 4875);
FORCEPROP 1 LASTPIN (-3200 4825) $PN 1
J 0
(-3188 4837);
DISPLAY 0.489362 (-3188 4837);
PAINT MONO (-3188 4837);
FORCEPROP 1 LASTPIN (-3000 4825) $PN 2
J 0
(-3038 4837);
DISPLAY 0.489362 (-3038 4837);
PAINT MONO (-3038 4837);
FORCEPROP 1 LAST VALUE 0
J 2
(-3200 4825);
DISPLAY 0.489362 (-3200 4825);
PAINT SKYBLUE (-3200 4825);
FORCEPROP 2 LAST CDS_LIB pure_quanta
J 0
(-3100 4825);
DISPLAY INVISIBLE (-3100 4825);
FORCEPROP 1 LAST PATH I362
J 0
(-3150 4975);
DISPLAY 0.978723 (-3150 4975);
PAINT WHITE (-3150 4975);
DISPLAY INVISIBLE (-3150 4975);
FORCEPROP 1 LAST WATTAGE 1/16W
J 2
(-2700 4750);
DISPLAY 0.489362 (-2700 4750);
PAINT SKYBLUE (-2700 4750);
DISPLAY INVISIBLE (-2700 4750);
FORCEPROP 1 LAST MATERIAL CHIP
J 0
(-2675 4750);
DISPLAY 0.489362 (-2675 4750);
PAINT SKYBLUE (-2675 4750);
DISPLAY INVISIBLE (-2675 4750);
FORCEPROP 1 LAST TOLERANCE 5%
J 0
(-3125 4750);
DISPLAY 0.489362 (-3125 4750);
PAINT SKYBLUE (-3125 4750);
DISPLAY INVISIBLE (-3125 4750);
FORCEPROP 1 LAST PART_NUMBER CS00002JB38
J 0
(-3075 4875);
DISPLAY 0.489362 (-3075 4875);
PAINT SKYBLUE (-3075 4875);
DISPLAY INVISIBLE (-3075 4875);
FORCEPROP 1 LAST PACK_TYPE 0402LF
J 0
(-3050 4750);
DISPLAY 0.489362 (-3050 4750);
PAINT SKYBLUE (-3050 4750);
DISPLAY INVISIBLE (-3050 4750);
FORCEADD Q_RES..1
(-3100 4675);
FORCEPROP 1 LAST LOCATION R928
J 0
(-2975 4675);
DISPLAY 0.489362 (-2975 4675);
PAINT SKYBLUE (-2975 4675);
FORCEPROP 0 LAST $SEC 1
J 0
(-2975 4725);
DISPLAY 0.680851 (-2975 4725);
PAINT MONO (-2975 4725);
DISPLAY INVISIBLE (-2975 4725);
FORCEPROP 0 LAST CDS_SEC 1
J 0
(-2975 4725);
DISPLAY 0.680851 (-2975 4725);
DISPLAY INVISIBLE (-2975 4725);
FORCEPROP 1 LASTPIN (-3200 4675) $PN 1
J 0
(-3188 4687);
DISPLAY 0.489362 (-3188 4687);
PAINT MONO (-3188 4687);
FORCEPROP 1 LASTPIN (-3000 4675) $PN 2
J 0
(-3038 4687);
DISPLAY 0.489362 (-3038 4687);
PAINT MONO (-3038 4687);
FORCEPROP 1 LAST VALUE 0
J 2
(-3200 4675);
DISPLAY 0.489362 (-3200 4675);
PAINT SKYBLUE (-3200 4675);
FORCEPROP 2 LAST CDS_LIB pure_quanta
J 0
(-3100 4675);
DISPLAY INVISIBLE (-3100 4675);
FORCEPROP 1 LAST PATH I363
J 0
(-3150 4825);
DISPLAY 0.978723 (-3150 4825);
PAINT WHITE (-3150 4825);
DISPLAY INVISIBLE (-3150 4825);
FORCEPROP 1 LAST WATTAGE 1/16W
J 2
(-2700 4600);
DISPLAY 0.489362 (-2700 4600);
PAINT SKYBLUE (-2700 4600);
DISPLAY INVISIBLE (-2700 4600);
FORCEPROP 1 LAST MATERIAL CHIP
J 0
(-2675 4600);
DISPLAY 0.489362 (-2675 4600);
PAINT SKYBLUE (-2675 4600);
DISPLAY INVISIBLE (-2675 4600);
FORCEPROP 1 LAST TOLERANCE 5%
J 0
(-3125 4600);
DISPLAY 0.489362 (-3125 4600);
PAINT SKYBLUE (-3125 4600);
DISPLAY INVISIBLE (-3125 4600);
FORCEPROP 1 LAST PART_NUMBER CS00002JB38
J 0
(-3075 4725);
DISPLAY 0.489362 (-3075 4725);
PAINT SKYBLUE (-3075 4725);
DISPLAY INVISIBLE (-3075 4725);
FORCEPROP 1 LAST PACK_TYPE 0402LF
J 0
(-3050 4600);
DISPLAY 0.489362 (-3050 4600);
PAINT SKYBLUE (-3050 4600);
DISPLAY INVISIBLE (-3050 4600);
FORCEADD Q_RES..1
(-3100 4725);
FORCEPROP 1 LAST LOCATION R862
J 0
(-2975 4725);
DISPLAY 0.489362 (-2975 4725);
PAINT SKYBLUE (-2975 4725);
FORCEPROP 0 LAST $SEC 1
J 0
(-2975 4775);
DISPLAY 0.680851 (-2975 4775);
PAINT MONO (-2975 4775);
DISPLAY INVISIBLE (-2975 4775);
FORCEPROP 0 LAST CDS_SEC 1
J 0
(-2975 4775);
DISPLAY 0.680851 (-2975 4775);
DISPLAY INVISIBLE (-2975 4775);
FORCEPROP 1 LASTPIN (-3200 4725) $PN 1
J 0
(-3188 4737);
DISPLAY 0.489362 (-3188 4737);
PAINT MONO (-3188 4737);
FORCEPROP 1 LASTPIN (-3000 4725) $PN 2
J 0
(-3038 4737);
DISPLAY 0.489362 (-3038 4737);
PAINT MONO (-3038 4737);
FORCEPROP 1 LAST VALUE 0
J 2
(-3200 4725);
DISPLAY 0.489362 (-3200 4725);
PAINT SKYBLUE (-3200 4725);
FORCEPROP 2 LAST CDS_LIB pure_quanta
J 0
(-3100 4725);
DISPLAY INVISIBLE (-3100 4725);
FORCEPROP 1 LAST PATH I364
J 0
(-3150 4875);
DISPLAY 0.978723 (-3150 4875);
PAINT WHITE (-3150 4875);
DISPLAY INVISIBLE (-3150 4875);
FORCEPROP 1 LAST WATTAGE 1/16W
J 2
(-2700 4650);
DISPLAY 0.489362 (-2700 4650);
PAINT SKYBLUE (-2700 4650);
DISPLAY INVISIBLE (-2700 4650);
FORCEPROP 1 LAST MATERIAL CHIP
J 0
(-2675 4650);
DISPLAY 0.489362 (-2675 4650);
PAINT SKYBLUE (-2675 4650);
DISPLAY INVISIBLE (-2675 4650);
FORCEPROP 1 LAST TOLERANCE 5%
J 0
(-3125 4650);
DISPLAY 0.489362 (-3125 4650);
PAINT SKYBLUE (-3125 4650);
DISPLAY INVISIBLE (-3125 4650);
FORCEPROP 1 LAST PART_NUMBER CS00002JB38
J 0
(-3075 4775);
DISPLAY 0.489362 (-3075 4775);
PAINT SKYBLUE (-3075 4775);
DISPLAY INVISIBLE (-3075 4775);
FORCEPROP 1 LAST PACK_TYPE 0402LF
J 0
(-3050 4650);
DISPLAY 0.489362 (-3050 4650);
PAINT SKYBLUE (-3050 4650);
DISPLAY INVISIBLE (-3050 4650);
FORCEADD UNIVERSAL_GND..1
(-675 2300);
FORCEPROP 3 LASTPIN (-675 2350) SIG_NAME GND\g
J 0
(-665 2360);
DISPLAY 0.659574 (-665 2360);
PAINT MONO (-665 2360);
DISPLAY INVISIBLE (-665 2360);
FORCEPROP 2 LAST CDS_LIB pure_quanta_power
J 0
(-675 2300);
DISPLAY INVISIBLE (-675 2300);
FORCEPROP 1 LAST PATH I365
J 0
(-600 2300);
DISPLAY 0.872340 (-600 2300);
PAINT AQUA (-600 2300);
DISPLAY INVISIBLE (-600 2300);
FORCEPROP 1 LAST HDL_POWER GND
J 1
(-650 2225);
DISPLAY 0.872340 (-650 2225);
PAINT GREEN (-650 2225);
DISPLAY INVISIBLE (-650 2225);
FORCEADD OFFPAGE..2
R 2
(-1975 2450);
FORCEPROP 2 LAST $XR0 54 
J 0
(-2229 2450);
DISPLAY 0.638298 (-2229 2450);
PAINT MONO (-2229 2450);
FORCEPROP 2 LAST PATH I366
J 0
(-2225 2500);
DISPLAY 0.680851 (-2225 2500);
DISPLAY INVISIBLE (-2225 2500);
FORCEPROP 1 LAST COMMENT_BODY TRUE
J 2
(-1930 2355);
DISPLAY 0.872340 (-1930 2355);
PAINT PEACH (-1930 2355);
DISPLAY INVISIBLE (-1930 2355);
FORCEPROP 1 LAST OFFPAGE TRUE
J 2
(-2300 2325);
DISPLAY 0.872340 (-2300 2325);
PAINT GREEN (-2300 2325);
DISPLAY INVISIBLE (-2300 2325);
FORCEPROP 2 LAST CDS_LIB standard
J 0
(-1975 2450);
DISPLAY INVISIBLE (-1975 2450);
FORCEADD OFFPAGE..2
R 2
(-1975 2500);
FORCEPROP 2 LAST $XR0 54 
J 0
(-2229 2500);
DISPLAY 0.638298 (-2229 2500);
PAINT MONO (-2229 2500);
FORCEPROP 2 LAST PATH I367
J 0
(-2225 2550);
DISPLAY 0.680851 (-2225 2550);
DISPLAY INVISIBLE (-2225 2550);
FORCEPROP 1 LAST COMMENT_BODY TRUE
J 2
(-1930 2405);
DISPLAY 0.872340 (-1930 2405);
PAINT PEACH (-1930 2405);
DISPLAY INVISIBLE (-1930 2405);
FORCEPROP 1 LAST OFFPAGE TRUE
J 2
(-2300 2375);
DISPLAY 0.872340 (-2300 2375);
PAINT GREEN (-2300 2375);
DISPLAY INVISIBLE (-2300 2375);
FORCEPROP 2 LAST CDS_LIB standard
J 0
(-1975 2500);
DISPLAY INVISIBLE (-1975 2500);
FORCEADD OFFPAGE..2
R 2
(-1975 2600);
FORCEPROP 2 LAST $XR0 54 
J 0
(-2229 2600);
DISPLAY 0.638298 (-2229 2600);
PAINT MONO (-2229 2600);
FORCEPROP 2 LAST PATH I368
J 0
(-2225 2650);
DISPLAY 0.680851 (-2225 2650);
DISPLAY INVISIBLE (-2225 2650);
FORCEPROP 1 LAST COMMENT_BODY TRUE
J 2
(-1930 2505);
DISPLAY 0.872340 (-1930 2505);
PAINT PEACH (-1930 2505);
DISPLAY INVISIBLE (-1930 2505);
FORCEPROP 1 LAST OFFPAGE TRUE
J 2
(-2300 2475);
DISPLAY 0.872340 (-2300 2475);
PAINT GREEN (-2300 2475);
DISPLAY INVISIBLE (-2300 2475);
FORCEPROP 2 LAST CDS_LIB standard
J 0
(-1975 2600);
DISPLAY INVISIBLE (-1975 2600);
FORCEADD OFFPAGE..2
R 2
(-1975 2550);
FORCEPROP 2 LAST $XR0 54 
J 0
(-2229 2550);
DISPLAY 0.638298 (-2229 2550);
PAINT MONO (-2229 2550);
FORCEPROP 2 LAST PATH I369
J 0
(-2225 2600);
DISPLAY 0.680851 (-2225 2600);
DISPLAY INVISIBLE (-2225 2600);
FORCEPROP 1 LAST COMMENT_BODY TRUE
J 2
(-1930 2455);
DISPLAY 0.872340 (-1930 2455);
PAINT PEACH (-1930 2455);
DISPLAY INVISIBLE (-1930 2455);
FORCEPROP 1 LAST OFFPAGE TRUE
J 2
(-2300 2425);
DISPLAY 0.872340 (-2300 2425);
PAINT GREEN (-2300 2425);
DISPLAY INVISIBLE (-2300 2425);
FORCEPROP 2 LAST CDS_LIB standard
J 0
(-1975 2550);
DISPLAY INVISIBLE (-1975 2550);
FORCEADD UNIVERSAL_GND..1
(-150 3350);
FORCEPROP 3 LASTPIN (-150 3400) SIG_NAME GND\g
J 0
(-140 3410);
DISPLAY 0.659574 (-140 3410);
PAINT MONO (-140 3410);
DISPLAY INVISIBLE (-140 3410);
FORCEPROP 2 LAST CDS_LIB pure_quanta_power
J 0
(-150 3350);
DISPLAY INVISIBLE (-150 3350);
FORCEPROP 1 LAST PATH I370
J 0
(-75 3350);
DISPLAY 0.872340 (-75 3350);
PAINT AQUA (-75 3350);
DISPLAY INVISIBLE (-75 3350);
FORCEPROP 1 LAST HDL_POWER GND
J 1
(-125 3275);
DISPLAY 0.872340 (-125 3275);
PAINT GREEN (-125 3275);
DISPLAY INVISIBLE (-125 3275);
FORCEADD Q_RES..1
(-1425 3650);
FORCEPROP 1 LAST LOCATION R929
J 0
(-1325 3650);
DISPLAY 0.489362 (-1325 3650);
PAINT SKYBLUE (-1325 3650);
FORCEPROP 0 LAST $SEC 1
J 0
(-1325 3700);
DISPLAY 0.680851 (-1325 3700);
PAINT MONO (-1325 3700);
DISPLAY INVISIBLE (-1325 3700);
FORCEPROP 0 LAST CDS_SEC 1
J 0
(-1325 3700);
DISPLAY 0.680851 (-1325 3700);
DISPLAY INVISIBLE (-1325 3700);
FORCEPROP 1 LASTPIN (-1525 3650) $PN 1
J 0
(-1513 3662);
DISPLAY 0.489362 (-1513 3662);
PAINT MONO (-1513 3662);
FORCEPROP 1 LASTPIN (-1325 3650) $PN 2
J 0
(-1363 3662);
DISPLAY 0.489362 (-1363 3662);
PAINT MONO (-1363 3662);
FORCEPROP 1 LAST VALUE 0
J 2
(-1525 3650);
DISPLAY 0.489362 (-1525 3650);
PAINT SKYBLUE (-1525 3650);
FORCEPROP 2 LAST CDS_LIB pure_quanta
J 0
(-1425 3650);
DISPLAY INVISIBLE (-1425 3650);
FORCEPROP 1 LAST PATH I371
J 0
(-1475 3800);
DISPLAY 0.978723 (-1475 3800);
PAINT WHITE (-1475 3800);
DISPLAY INVISIBLE (-1475 3800);
FORCEPROP 1 LAST WATTAGE 1/16W
J 2
(-1025 3575);
DISPLAY 0.489362 (-1025 3575);
PAINT SKYBLUE (-1025 3575);
DISPLAY INVISIBLE (-1025 3575);
FORCEPROP 1 LAST MATERIAL CHIP
J 0
(-1000 3575);
DISPLAY 0.489362 (-1000 3575);
PAINT SKYBLUE (-1000 3575);
DISPLAY INVISIBLE (-1000 3575);
FORCEPROP 1 LAST TOLERANCE 5%
J 0
(-1450 3575);
DISPLAY 0.489362 (-1450 3575);
PAINT SKYBLUE (-1450 3575);
DISPLAY INVISIBLE (-1450 3575);
FORCEPROP 1 LAST PART_NUMBER CS00002JB38
J 0
(-1400 3700);
DISPLAY 0.489362 (-1400 3700);
PAINT SKYBLUE (-1400 3700);
DISPLAY INVISIBLE (-1400 3700);
FORCEPROP 1 LAST PACK_TYPE 0402LF
J 0
(-1375 3575);
DISPLAY 0.489362 (-1375 3575);
PAINT SKYBLUE (-1375 3575);
DISPLAY INVISIBLE (-1375 3575);
FORCEADD Q_RES..1
(-1425 3600);
FORCEPROP 1 LAST LOCATION R930
J 0
(-1325 3600);
DISPLAY 0.489362 (-1325 3600);
PAINT SKYBLUE (-1325 3600);
FORCEPROP 0 LAST $SEC 1
J 0
(-1325 3650);
DISPLAY 0.680851 (-1325 3650);
PAINT MONO (-1325 3650);
DISPLAY INVISIBLE (-1325 3650);
FORCEPROP 0 LAST CDS_SEC 1
J 0
(-1325 3650);
DISPLAY 0.680851 (-1325 3650);
DISPLAY INVISIBLE (-1325 3650);
FORCEPROP 1 LASTPIN (-1525 3600) $PN 1
J 0
(-1513 3612);
DISPLAY 0.489362 (-1513 3612);
PAINT MONO (-1513 3612);
FORCEPROP 1 LASTPIN (-1325 3600) $PN 2
J 0
(-1363 3612);
DISPLAY 0.489362 (-1363 3612);
PAINT MONO (-1363 3612);
FORCEPROP 1 LAST VALUE 0
J 2
(-1525 3600);
DISPLAY 0.489362 (-1525 3600);
PAINT SKYBLUE (-1525 3600);
FORCEPROP 2 LAST CDS_LIB pure_quanta
J 0
(-1425 3600);
DISPLAY INVISIBLE (-1425 3600);
FORCEPROP 1 LAST PATH I372
J 0
(-1475 3750);
DISPLAY 0.978723 (-1475 3750);
PAINT WHITE (-1475 3750);
DISPLAY INVISIBLE (-1475 3750);
FORCEPROP 1 LAST WATTAGE 1/16W
J 2
(-1025 3525);
DISPLAY 0.489362 (-1025 3525);
PAINT SKYBLUE (-1025 3525);
DISPLAY INVISIBLE (-1025 3525);
FORCEPROP 1 LAST MATERIAL CHIP
J 0
(-1000 3525);
DISPLAY 0.489362 (-1000 3525);
PAINT SKYBLUE (-1000 3525);
DISPLAY INVISIBLE (-1000 3525);
FORCEPROP 1 LAST TOLERANCE 5%
J 0
(-1450 3525);
DISPLAY 0.489362 (-1450 3525);
PAINT SKYBLUE (-1450 3525);
DISPLAY INVISIBLE (-1450 3525);
FORCEPROP 1 LAST PART_NUMBER CS00002JB38
J 0
(-1400 3650);
DISPLAY 0.489362 (-1400 3650);
PAINT SKYBLUE (-1400 3650);
DISPLAY INVISIBLE (-1400 3650);
FORCEPROP 1 LAST PACK_TYPE 0402LF
J 0
(-1375 3525);
DISPLAY 0.489362 (-1375 3525);
PAINT SKYBLUE (-1375 3525);
DISPLAY INVISIBLE (-1375 3525);
FORCEADD Q_RES..1
(-1425 3500);
FORCEPROP 1 LAST LOCATION R932
J 0
(-1325 3500);
DISPLAY 0.489362 (-1325 3500);
PAINT SKYBLUE (-1325 3500);
FORCEPROP 0 LAST $SEC 1
J 0
(-1325 3550);
DISPLAY 0.680851 (-1325 3550);
PAINT MONO (-1325 3550);
DISPLAY INVISIBLE (-1325 3550);
FORCEPROP 0 LAST CDS_SEC 1
J 0
(-1325 3550);
DISPLAY 0.680851 (-1325 3550);
DISPLAY INVISIBLE (-1325 3550);
FORCEPROP 1 LASTPIN (-1525 3500) $PN 1
J 0
(-1513 3512);
DISPLAY 0.489362 (-1513 3512);
PAINT MONO (-1513 3512);
FORCEPROP 1 LASTPIN (-1325 3500) $PN 2
J 0
(-1363 3512);
DISPLAY 0.489362 (-1363 3512);
PAINT MONO (-1363 3512);
FORCEPROP 1 LAST VALUE 0
J 2
(-1525 3500);
DISPLAY 0.489362 (-1525 3500);
PAINT SKYBLUE (-1525 3500);
FORCEPROP 2 LAST CDS_LIB pure_quanta
J 0
(-1425 3500);
DISPLAY INVISIBLE (-1425 3500);
FORCEPROP 1 LAST PATH I373
J 0
(-1475 3650);
DISPLAY 0.978723 (-1475 3650);
PAINT WHITE (-1475 3650);
DISPLAY INVISIBLE (-1475 3650);
FORCEPROP 1 LAST WATTAGE 1/16W
J 2
(-1025 3425);
DISPLAY 0.489362 (-1025 3425);
PAINT SKYBLUE (-1025 3425);
DISPLAY INVISIBLE (-1025 3425);
FORCEPROP 1 LAST MATERIAL CHIP
J 0
(-1000 3425);
DISPLAY 0.489362 (-1000 3425);
PAINT SKYBLUE (-1000 3425);
DISPLAY INVISIBLE (-1000 3425);
FORCEPROP 1 LAST TOLERANCE 5%
J 0
(-1450 3425);
DISPLAY 0.489362 (-1450 3425);
PAINT SKYBLUE (-1450 3425);
DISPLAY INVISIBLE (-1450 3425);
FORCEPROP 1 LAST PART_NUMBER CS00002JB38
J 0
(-1400 3550);
DISPLAY 0.489362 (-1400 3550);
PAINT SKYBLUE (-1400 3550);
DISPLAY INVISIBLE (-1400 3550);
FORCEPROP 1 LAST PACK_TYPE 0402LF
J 0
(-1375 3425);
DISPLAY 0.489362 (-1375 3425);
PAINT SKYBLUE (-1375 3425);
DISPLAY INVISIBLE (-1375 3425);
FORCEADD Q_RES..1
(-1425 3550);
FORCEPROP 1 LAST LOCATION R931
J 0
(-1325 3550);
DISPLAY 0.489362 (-1325 3550);
PAINT SKYBLUE (-1325 3550);
FORCEPROP 0 LAST $SEC 1
J 0
(-1325 3600);
DISPLAY 0.680851 (-1325 3600);
PAINT MONO (-1325 3600);
DISPLAY INVISIBLE (-1325 3600);
FORCEPROP 0 LAST CDS_SEC 1
J 0
(-1325 3600);
DISPLAY 0.680851 (-1325 3600);
DISPLAY INVISIBLE (-1325 3600);
FORCEPROP 1 LASTPIN (-1525 3550) $PN 1
J 0
(-1513 3562);
DISPLAY 0.489362 (-1513 3562);
PAINT MONO (-1513 3562);
FORCEPROP 1 LASTPIN (-1325 3550) $PN 2
J 0
(-1363 3562);
DISPLAY 0.489362 (-1363 3562);
PAINT MONO (-1363 3562);
FORCEPROP 1 LAST VALUE 0
J 2
(-1525 3550);
DISPLAY 0.489362 (-1525 3550);
PAINT SKYBLUE (-1525 3550);
FORCEPROP 2 LAST CDS_LIB pure_quanta
J 0
(-1425 3550);
DISPLAY INVISIBLE (-1425 3550);
FORCEPROP 1 LAST PATH I374
J 0
(-1475 3700);
DISPLAY 0.978723 (-1475 3700);
PAINT WHITE (-1475 3700);
DISPLAY INVISIBLE (-1475 3700);
FORCEPROP 1 LAST WATTAGE 1/16W
J 2
(-1025 3475);
DISPLAY 0.489362 (-1025 3475);
PAINT SKYBLUE (-1025 3475);
DISPLAY INVISIBLE (-1025 3475);
FORCEPROP 1 LAST MATERIAL CHIP
J 0
(-1000 3475);
DISPLAY 0.489362 (-1000 3475);
PAINT SKYBLUE (-1000 3475);
DISPLAY INVISIBLE (-1000 3475);
FORCEPROP 1 LAST TOLERANCE 5%
J 0
(-1450 3475);
DISPLAY 0.489362 (-1450 3475);
PAINT SKYBLUE (-1450 3475);
DISPLAY INVISIBLE (-1450 3475);
FORCEPROP 1 LAST PART_NUMBER CS00002JB38
J 0
(-1400 3600);
DISPLAY 0.489362 (-1400 3600);
PAINT SKYBLUE (-1400 3600);
DISPLAY INVISIBLE (-1400 3600);
FORCEPROP 1 LAST PACK_TYPE 0402LF
J 0
(-1375 3475);
DISPLAY 0.489362 (-1375 3475);
PAINT SKYBLUE (-1375 3475);
DISPLAY INVISIBLE (-1375 3475);
FORCEADD OFFPAGE..2
R 2
(-2025 3650);
FORCEPROP 2 LAST $XR1 81 
J 0
(-2339 3650);
DISPLAY 0.638298 (-2339 3650);
PAINT MONO (-2339 3650);
FORCEPROP 2 LAST $XR0 54 
J 0
(-2249 3650);
DISPLAY 0.638298 (-2249 3650);
PAINT MONO (-2249 3650);
FORCEPROP 2 LAST PATH I375
J 0
(-2275 3700);
DISPLAY 0.680851 (-2275 3700);
DISPLAY INVISIBLE (-2275 3700);
FORCEPROP 1 LAST COMMENT_BODY TRUE
J 2
(-1980 3555);
DISPLAY 0.872340 (-1980 3555);
PAINT PEACH (-1980 3555);
DISPLAY INVISIBLE (-1980 3555);
FORCEPROP 1 LAST OFFPAGE TRUE
J 2
(-2350 3525);
DISPLAY 0.872340 (-2350 3525);
PAINT GREEN (-2350 3525);
DISPLAY INVISIBLE (-2350 3525);
FORCEPROP 2 LAST CDS_LIB standard
J 0
(-2025 3650);
DISPLAY INVISIBLE (-2025 3650);
FORCEADD OFFPAGE..2
R 2
(-2025 3600);
FORCEPROP 2 LAST $XR1 81 
J 0
(-2339 3600);
DISPLAY 0.638298 (-2339 3600);
PAINT MONO (-2339 3600);
FORCEPROP 2 LAST $XR0 54 
J 0
(-2249 3600);
DISPLAY 0.638298 (-2249 3600);
PAINT MONO (-2249 3600);
FORCEPROP 2 LAST PATH I376
J 0
(-2275 3650);
DISPLAY 0.680851 (-2275 3650);
DISPLAY INVISIBLE (-2275 3650);
FORCEPROP 1 LAST COMMENT_BODY TRUE
J 2
(-1980 3505);
DISPLAY 0.872340 (-1980 3505);
PAINT PEACH (-1980 3505);
DISPLAY INVISIBLE (-1980 3505);
FORCEPROP 1 LAST OFFPAGE TRUE
J 2
(-2350 3475);
DISPLAY 0.872340 (-2350 3475);
PAINT GREEN (-2350 3475);
DISPLAY INVISIBLE (-2350 3475);
FORCEPROP 2 LAST CDS_LIB standard
J 0
(-2025 3600);
DISPLAY INVISIBLE (-2025 3600);
FORCEADD OFFPAGE..2
R 2
(-2025 3550);
FORCEPROP 2 LAST $XR1 81 
J 0
(-2339 3550);
DISPLAY 0.638298 (-2339 3550);
PAINT MONO (-2339 3550);
FORCEPROP 2 LAST $XR0 54 
J 0
(-2249 3550);
DISPLAY 0.638298 (-2249 3550);
PAINT MONO (-2249 3550);
FORCEPROP 2 LAST PATH I377
J 0
(-2275 3600);
DISPLAY 0.680851 (-2275 3600);
DISPLAY INVISIBLE (-2275 3600);
FORCEPROP 1 LAST COMMENT_BODY TRUE
J 2
(-1980 3455);
DISPLAY 0.872340 (-1980 3455);
PAINT PEACH (-1980 3455);
DISPLAY INVISIBLE (-1980 3455);
FORCEPROP 1 LAST OFFPAGE TRUE
J 2
(-2350 3425);
DISPLAY 0.872340 (-2350 3425);
PAINT GREEN (-2350 3425);
DISPLAY INVISIBLE (-2350 3425);
FORCEPROP 2 LAST CDS_LIB standard
J 0
(-2025 3550);
DISPLAY INVISIBLE (-2025 3550);
FORCEADD OFFPAGE..2
R 2
(-2025 3500);
FORCEPROP 2 LAST $XR1 81 
J 0
(-2339 3500);
DISPLAY 0.638298 (-2339 3500);
PAINT MONO (-2339 3500);
FORCEPROP 2 LAST $XR0 54 
J 0
(-2249 3500);
DISPLAY 0.638298 (-2249 3500);
PAINT MONO (-2249 3500);
FORCEPROP 2 LAST PATH I378
J 0
(-2275 3550);
DISPLAY 0.680851 (-2275 3550);
DISPLAY INVISIBLE (-2275 3550);
FORCEPROP 1 LAST COMMENT_BODY TRUE
J 2
(-1980 3405);
DISPLAY 0.872340 (-1980 3405);
PAINT PEACH (-1980 3405);
DISPLAY INVISIBLE (-1980 3405);
FORCEPROP 1 LAST OFFPAGE TRUE
J 2
(-2350 3375);
DISPLAY 0.872340 (-2350 3375);
PAINT GREEN (-2350 3375);
DISPLAY INVISIBLE (-2350 3375);
FORCEPROP 2 LAST CDS_LIB standard
J 0
(-2025 3500);
DISPLAY INVISIBLE (-2025 3500);
FORCEADD OFFPAGE..2
(-7750 3325);
FORCEPROP 2 LAST $XR1 81 
J 0
(-7471 3325);
DISPLAY 0.638298 (-7471 3325);
PAINT MONO (-7471 3325);
FORCEPROP 2 LAST $XR0 54 
J 0
(-7561 3325);
DISPLAY 0.638298 (-7561 3325);
PAINT MONO (-7561 3325);
FORCEPROP 2 LAST PATH I379
J 0
(-7450 3375);
DISPLAY 0.680851 (-7450 3375);
DISPLAY INVISIBLE (-7450 3375);
FORCEPROP 1 LAST COMMENT_BODY TRUE
J 0
(-7795 3230);
DISPLAY 0.872340 (-7795 3230);
PAINT PEACH (-7795 3230);
DISPLAY INVISIBLE (-7795 3230);
FORCEPROP 1 LAST OFFPAGE TRUE
J 0
(-7425 3200);
DISPLAY 0.872340 (-7425 3200);
PAINT GREEN (-7425 3200);
DISPLAY INVISIBLE (-7425 3200);
FORCEPROP 2 LAST CDS_LIB standard
J 0
(-7750 3325);
DISPLAY INVISIBLE (-7750 3325);
FORCEADD OFFPAGE..2
(-7750 3275);
FORCEPROP 2 LAST $XR1 81 
J 0
(-7471 3275);
DISPLAY 0.638298 (-7471 3275);
PAINT MONO (-7471 3275);
FORCEPROP 2 LAST $XR0 54 
J 0
(-7561 3275);
DISPLAY 0.638298 (-7561 3275);
PAINT MONO (-7561 3275);
FORCEPROP 2 LAST PATH I380
J 0
(-7450 3325);
DISPLAY 0.680851 (-7450 3325);
DISPLAY INVISIBLE (-7450 3325);
FORCEPROP 1 LAST COMMENT_BODY TRUE
J 0
(-7795 3180);
DISPLAY 0.872340 (-7795 3180);
PAINT PEACH (-7795 3180);
DISPLAY INVISIBLE (-7795 3180);
FORCEPROP 1 LAST OFFPAGE TRUE
J 0
(-7425 3150);
DISPLAY 0.872340 (-7425 3150);
PAINT GREEN (-7425 3150);
DISPLAY INVISIBLE (-7425 3150);
FORCEPROP 2 LAST CDS_LIB standard
J 0
(-7750 3275);
DISPLAY INVISIBLE (-7750 3275);
FORCEADD OFFPAGE..2
(-7750 3225);
FORCEPROP 2 LAST $XR1 81 
J 0
(-7471 3225);
DISPLAY 0.638298 (-7471 3225);
PAINT MONO (-7471 3225);
FORCEPROP 2 LAST $XR0 54 
J 0
(-7561 3225);
DISPLAY 0.638298 (-7561 3225);
PAINT MONO (-7561 3225);
FORCEPROP 2 LAST PATH I381
J 0
(-7450 3275);
DISPLAY 0.680851 (-7450 3275);
DISPLAY INVISIBLE (-7450 3275);
FORCEPROP 1 LAST COMMENT_BODY TRUE
J 0
(-7795 3130);
DISPLAY 0.872340 (-7795 3130);
PAINT PEACH (-7795 3130);
DISPLAY INVISIBLE (-7795 3130);
FORCEPROP 1 LAST OFFPAGE TRUE
J 0
(-7425 3100);
DISPLAY 0.872340 (-7425 3100);
PAINT GREEN (-7425 3100);
DISPLAY INVISIBLE (-7425 3100);
FORCEPROP 2 LAST CDS_LIB standard
J 0
(-7750 3225);
DISPLAY INVISIBLE (-7750 3225);
FORCEADD OFFPAGE..2
(-7750 3175);
FORCEPROP 2 LAST $XR1 81 
J 0
(-7471 3175);
DISPLAY 0.638298 (-7471 3175);
PAINT MONO (-7471 3175);
FORCEPROP 2 LAST $XR0 54 
J 0
(-7561 3175);
DISPLAY 0.638298 (-7561 3175);
PAINT MONO (-7561 3175);
FORCEPROP 2 LAST PATH I382
J 0
(-7450 3225);
DISPLAY 0.680851 (-7450 3225);
DISPLAY INVISIBLE (-7450 3225);
FORCEPROP 1 LAST COMMENT_BODY TRUE
J 0
(-7795 3080);
DISPLAY 0.872340 (-7795 3080);
PAINT PEACH (-7795 3080);
DISPLAY INVISIBLE (-7795 3080);
FORCEPROP 1 LAST OFFPAGE TRUE
J 0
(-7425 3050);
DISPLAY 0.872340 (-7425 3050);
PAINT GREEN (-7425 3050);
DISPLAY INVISIBLE (-7425 3050);
FORCEPROP 2 LAST CDS_LIB standard
J 0
(-7750 3175);
DISPLAY INVISIBLE (-7750 3175);
FORCEADD OFFPAGE..2
(-7750 3125);
FORCEPROP 2 LAST $XR1 81 
J 0
(-7471 3125);
DISPLAY 0.638298 (-7471 3125);
PAINT MONO (-7471 3125);
FORCEPROP 2 LAST $XR0 54 
J 0
(-7561 3125);
DISPLAY 0.638298 (-7561 3125);
PAINT MONO (-7561 3125);
FORCEPROP 2 LAST PATH I384
J 0
(-7450 3175);
DISPLAY 0.680851 (-7450 3175);
DISPLAY INVISIBLE (-7450 3175);
FORCEPROP 1 LAST COMMENT_BODY TRUE
J 0
(-7795 3030);
DISPLAY 0.872340 (-7795 3030);
PAINT PEACH (-7795 3030);
DISPLAY INVISIBLE (-7795 3030);
FORCEPROP 1 LAST OFFPAGE TRUE
J 0
(-7425 3000);
DISPLAY 0.872340 (-7425 3000);
PAINT GREEN (-7425 3000);
DISPLAY INVISIBLE (-7425 3000);
FORCEPROP 2 LAST CDS_LIB standard
J 0
(-7750 3125);
DISPLAY INVISIBLE (-7750 3125);
FORCEADD OFFPAGE..2
(-7750 3075);
FORCEPROP 2 LAST $XR1 81 
J 0
(-7471 3075);
DISPLAY 0.638298 (-7471 3075);
PAINT MONO (-7471 3075);
FORCEPROP 2 LAST $XR0 54 
J 0
(-7561 3075);
DISPLAY 0.638298 (-7561 3075);
PAINT MONO (-7561 3075);
FORCEPROP 2 LAST PATH I385
J 0
(-7450 3125);
DISPLAY 0.680851 (-7450 3125);
DISPLAY INVISIBLE (-7450 3125);
FORCEPROP 1 LAST COMMENT_BODY TRUE
J 0
(-7795 2980);
DISPLAY 0.872340 (-7795 2980);
PAINT PEACH (-7795 2980);
DISPLAY INVISIBLE (-7795 2980);
FORCEPROP 1 LAST OFFPAGE TRUE
J 0
(-7425 2950);
DISPLAY 0.872340 (-7425 2950);
PAINT GREEN (-7425 2950);
DISPLAY INVISIBLE (-7425 2950);
FORCEPROP 2 LAST CDS_LIB standard
J 0
(-7750 3075);
DISPLAY INVISIBLE (-7750 3075);
FORCEADD OFFPAGE..2
(-7750 3025);
FORCEPROP 2 LAST $XR1 81 
J 0
(-7471 3025);
DISPLAY 0.638298 (-7471 3025);
PAINT MONO (-7471 3025);
FORCEPROP 2 LAST $XR0 54 
J 0
(-7561 3025);
DISPLAY 0.638298 (-7561 3025);
PAINT MONO (-7561 3025);
FORCEPROP 2 LAST PATH I386
J 0
(-7450 3075);
DISPLAY 0.680851 (-7450 3075);
DISPLAY INVISIBLE (-7450 3075);
FORCEPROP 1 LAST COMMENT_BODY TRUE
J 0
(-7795 2930);
DISPLAY 0.872340 (-7795 2930);
PAINT PEACH (-7795 2930);
DISPLAY INVISIBLE (-7795 2930);
FORCEPROP 1 LAST OFFPAGE TRUE
J 0
(-7425 2900);
DISPLAY 0.872340 (-7425 2900);
PAINT GREEN (-7425 2900);
DISPLAY INVISIBLE (-7425 2900);
FORCEPROP 2 LAST CDS_LIB standard
J 0
(-7750 3025);
DISPLAY INVISIBLE (-7750 3025);
FORCEADD Q_RES..1
(-8750 3275);
FORCEPROP 1 LAST LOCATION R517
J 2
(-8925 3275);
DISPLAY 0.489362 (-8925 3275);
PAINT SKYBLUE (-8925 3275);
FORCEPROP 0 LAST $SEC 1
J 0
(-8625 3300);
DISPLAY 0.680851 (-8625 3300);
PAINT MONO (-8625 3300);
DISPLAY INVISIBLE (-8625 3300);
FORCEPROP 0 LAST CDS_SEC 1
J 0
(-8625 3300);
DISPLAY 0.680851 (-8625 3300);
DISPLAY INVISIBLE (-8625 3300);
FORCEPROP 1 LASTPIN (-8850 3275) $PN 1
J 0
(-8838 3287);
DISPLAY 0.489362 (-8838 3287);
PAINT MONO (-8838 3287);
FORCEPROP 1 LASTPIN (-8650 3275) $PN 2
J 0
(-8688 3287);
DISPLAY 0.489362 (-8688 3287);
PAINT MONO (-8688 3287);
FORCEPROP 1 LAST VALUE 2.2K
J 0
(-8625 3275);
DISPLAY 0.489362 (-8625 3275);
PAINT SKYBLUE (-8625 3275);
FORCEPROP 2 LAST CDS_LIB pure_quanta
J 0
(-8750 3275);
DISPLAY INVISIBLE (-8750 3275);
FORCEPROP 1 LAST PATH I387
J 0
(-8800 3425);
DISPLAY 0.978723 (-8800 3425);
PAINT WHITE (-8800 3425);
DISPLAY INVISIBLE (-8800 3425);
FORCEPROP 1 LAST WATTAGE 1/16W
J 2
(-8775 3125);
DISPLAY 0.510638 (-8775 3125);
PAINT SKYBLUE (-8775 3125);
DISPLAY INVISIBLE (-8775 3125);
FORCEPROP 1 LAST MATERIAL CHIP
J 0
(-8650 3250);
DISPLAY 0.489362 (-8650 3250);
PAINT SKYBLUE (-8650 3250);
DISPLAY INVISIBLE (-8650 3250);
FORCEPROP 1 LAST TOLERANCE 5%
J 0
(-8625 3275);
DISPLAY 0.510638 (-8625 3275);
PAINT SKYBLUE (-8625 3275);
DISPLAY INVISIBLE (-8625 3275);
FORCEPROP 1 LAST PART_NUMBER CS22202JB07
J 0
(-8800 3375);
DISPLAY 0.510638 (-8800 3375);
PAINT SKYBLUE (-8800 3375);
DISPLAY INVISIBLE (-8800 3375);
FORCEPROP 1 LAST PACK_TYPE 0402LF
J 0
(-8500 3125);
DISPLAY 0.510638 (-8500 3125);
PAINT SKYBLUE (-8500 3125);
DISPLAY INVISIBLE (-8500 3125);
FORCEADD Q_RES..1
(-8750 3325);
FORCEPROP 1 LAST LOCATION R522
J 2
(-8925 3325);
DISPLAY 0.489362 (-8925 3325);
PAINT SKYBLUE (-8925 3325);
FORCEPROP 0 LAST $SEC 1
J 0
(-8625 3350);
DISPLAY 0.680851 (-8625 3350);
PAINT MONO (-8625 3350);
DISPLAY INVISIBLE (-8625 3350);
FORCEPROP 0 LAST CDS_SEC 1
J 0
(-8625 3350);
DISPLAY 0.680851 (-8625 3350);
DISPLAY INVISIBLE (-8625 3350);
FORCEPROP 1 LASTPIN (-8850 3325) $PN 1
J 0
(-8838 3337);
DISPLAY 0.489362 (-8838 3337);
PAINT MONO (-8838 3337);
FORCEPROP 1 LASTPIN (-8650 3325) $PN 2
J 0
(-8688 3337);
DISPLAY 0.489362 (-8688 3337);
PAINT MONO (-8688 3337);
FORCEPROP 1 LAST VALUE 2.2K
J 0
(-8625 3325);
DISPLAY 0.489362 (-8625 3325);
PAINT SKYBLUE (-8625 3325);
FORCEPROP 2 LAST CDS_LIB pure_quanta
J 0
(-8750 3325);
DISPLAY INVISIBLE (-8750 3325);
FORCEPROP 1 LAST PATH I388
J 0
(-8800 3475);
DISPLAY 0.978723 (-8800 3475);
PAINT WHITE (-8800 3475);
DISPLAY INVISIBLE (-8800 3475);
FORCEPROP 1 LAST WATTAGE 1/16W
J 2
(-8775 3175);
DISPLAY 0.510638 (-8775 3175);
PAINT SKYBLUE (-8775 3175);
DISPLAY INVISIBLE (-8775 3175);
FORCEPROP 1 LAST MATERIAL CHIP
J 0
(-8650 3300);
DISPLAY 0.489362 (-8650 3300);
PAINT SKYBLUE (-8650 3300);
DISPLAY INVISIBLE (-8650 3300);
FORCEPROP 1 LAST TOLERANCE 5%
J 0
(-8625 3325);
DISPLAY 0.510638 (-8625 3325);
PAINT SKYBLUE (-8625 3325);
DISPLAY INVISIBLE (-8625 3325);
FORCEPROP 1 LAST PART_NUMBER CS22202JB07
J 0
(-8800 3425);
DISPLAY 0.510638 (-8800 3425);
PAINT SKYBLUE (-8800 3425);
DISPLAY INVISIBLE (-8800 3425);
FORCEPROP 1 LAST PACK_TYPE 0402LF
J 0
(-8500 3175);
DISPLAY 0.510638 (-8500 3175);
PAINT SKYBLUE (-8500 3175);
DISPLAY INVISIBLE (-8500 3175);
FORCEADD UNIVERSAL_POWER..1
(-9050 3600);
FORCEPROP 3 LASTPIN (-9050 3550) SIG_NAME P3V3_STBY\g
J 0
(-9040 3560);
DISPLAY 0.659574 (-9040 3560);
PAINT MONO (-9040 3560);
DISPLAY INVISIBLE (-9040 3560);
FORCEPROP 1 LAST HDL_POWER P3V3_STBY
J 1
(-9050 3650);
DISPLAY 0.489362 (-9050 3650);
PAINT GREEN (-9050 3650);
FORCEPROP 2 LAST CDS_LIB pure_quanta_power
J 0
(-9050 3600);
DISPLAY INVISIBLE (-9050 3600);
FORCEPROP 1 LAST PATH I389
J 0
(-9000 3625);
DISPLAY 0.872340 (-9000 3625);
PAINT AQUA (-9000 3625);
DISPLAY INVISIBLE (-9000 3625);
FORCEADD Q_RES..1
(-8750 3175);
FORCEPROP 1 LAST LOCATION R513
J 2
(-8925 3175);
DISPLAY 0.489362 (-8925 3175);
PAINT SKYBLUE (-8925 3175);
FORCEPROP 0 LAST $SEC 1
J 0
(-8625 3200);
DISPLAY 0.680851 (-8625 3200);
PAINT MONO (-8625 3200);
DISPLAY INVISIBLE (-8625 3200);
FORCEPROP 0 LAST CDS_SEC 1
J 0
(-8625 3200);
DISPLAY 0.680851 (-8625 3200);
DISPLAY INVISIBLE (-8625 3200);
FORCEPROP 1 LASTPIN (-8850 3175) $PN 1
J 0
(-8838 3187);
DISPLAY 0.489362 (-8838 3187);
PAINT MONO (-8838 3187);
FORCEPROP 1 LASTPIN (-8650 3175) $PN 2
J 0
(-8688 3187);
DISPLAY 0.489362 (-8688 3187);
PAINT MONO (-8688 3187);
FORCEPROP 1 LAST VALUE 2.2K
J 0
(-8625 3175);
DISPLAY 0.489362 (-8625 3175);
PAINT SKYBLUE (-8625 3175);
FORCEPROP 2 LAST CDS_LIB pure_quanta
J 0
(-8750 3175);
DISPLAY INVISIBLE (-8750 3175);
FORCEPROP 1 LAST PATH I390
J 0
(-8800 3325);
DISPLAY 0.978723 (-8800 3325);
PAINT WHITE (-8800 3325);
DISPLAY INVISIBLE (-8800 3325);
FORCEPROP 1 LAST WATTAGE 1/16W
J 2
(-8775 3025);
DISPLAY 0.510638 (-8775 3025);
PAINT SKYBLUE (-8775 3025);
DISPLAY INVISIBLE (-8775 3025);
FORCEPROP 1 LAST MATERIAL CHIP
J 0
(-8650 3150);
DISPLAY 0.489362 (-8650 3150);
PAINT SKYBLUE (-8650 3150);
DISPLAY INVISIBLE (-8650 3150);
FORCEPROP 1 LAST TOLERANCE 5%
J 0
(-8625 3175);
DISPLAY 0.510638 (-8625 3175);
PAINT SKYBLUE (-8625 3175);
DISPLAY INVISIBLE (-8625 3175);
FORCEPROP 1 LAST PART_NUMBER CS22202JB07
J 0
(-8800 3275);
DISPLAY 0.510638 (-8800 3275);
PAINT SKYBLUE (-8800 3275);
DISPLAY INVISIBLE (-8800 3275);
FORCEPROP 1 LAST PACK_TYPE 0402LF
J 0
(-8500 3025);
DISPLAY 0.510638 (-8500 3025);
PAINT SKYBLUE (-8500 3025);
DISPLAY INVISIBLE (-8500 3025);
FORCEADD Q_RES..1
(-8750 3225);
FORCEPROP 1 LAST LOCATION R515
J 2
(-8925 3225);
DISPLAY 0.489362 (-8925 3225);
PAINT SKYBLUE (-8925 3225);
FORCEPROP 0 LAST $SEC 1
J 0
(-8625 3250);
DISPLAY 0.680851 (-8625 3250);
PAINT MONO (-8625 3250);
DISPLAY INVISIBLE (-8625 3250);
FORCEPROP 0 LAST CDS_SEC 1
J 0
(-8625 3250);
DISPLAY 0.680851 (-8625 3250);
DISPLAY INVISIBLE (-8625 3250);
FORCEPROP 1 LASTPIN (-8850 3225) $PN 1
J 0
(-8838 3237);
DISPLAY 0.489362 (-8838 3237);
PAINT MONO (-8838 3237);
FORCEPROP 1 LASTPIN (-8650 3225) $PN 2
J 0
(-8688 3237);
DISPLAY 0.489362 (-8688 3237);
PAINT MONO (-8688 3237);
FORCEPROP 1 LAST VALUE 2.2K
J 0
(-8625 3225);
DISPLAY 0.489362 (-8625 3225);
PAINT SKYBLUE (-8625 3225);
FORCEPROP 2 LAST CDS_LIB pure_quanta
J 0
(-8750 3225);
DISPLAY INVISIBLE (-8750 3225);
FORCEPROP 1 LAST PATH I391
J 0
(-8800 3375);
DISPLAY 0.978723 (-8800 3375);
PAINT WHITE (-8800 3375);
DISPLAY INVISIBLE (-8800 3375);
FORCEPROP 1 LAST WATTAGE 1/16W
J 2
(-8775 3075);
DISPLAY 0.510638 (-8775 3075);
PAINT SKYBLUE (-8775 3075);
DISPLAY INVISIBLE (-8775 3075);
FORCEPROP 1 LAST MATERIAL CHIP
J 0
(-8650 3200);
DISPLAY 0.489362 (-8650 3200);
PAINT SKYBLUE (-8650 3200);
DISPLAY INVISIBLE (-8650 3200);
FORCEPROP 1 LAST TOLERANCE 5%
J 0
(-8625 3225);
DISPLAY 0.510638 (-8625 3225);
PAINT SKYBLUE (-8625 3225);
DISPLAY INVISIBLE (-8625 3225);
FORCEPROP 1 LAST PART_NUMBER CS22202JB07
J 0
(-8800 3325);
DISPLAY 0.510638 (-8800 3325);
PAINT SKYBLUE (-8800 3325);
DISPLAY INVISIBLE (-8800 3325);
FORCEPROP 1 LAST PACK_TYPE 0402LF
J 0
(-8500 3075);
DISPLAY 0.510638 (-8500 3075);
PAINT SKYBLUE (-8500 3075);
DISPLAY INVISIBLE (-8500 3075);
FORCEADD Q_RES..1
(-500 5575);
FORCEPROP 1 LAST LOCATION R520
J 0
(-750 5575);
DISPLAY 0.489362 (-750 5575);
PAINT SKYBLUE (-750 5575);
FORCEPROP 0 LAST $SEC 1
J 0
(-250 5600);
DISPLAY 0.680851 (-250 5600);
PAINT MONO (-250 5600);
DISPLAY INVISIBLE (-250 5600);
FORCEPROP 0 LAST CDS_SEC 1
J 0
(-250 5600);
DISPLAY 0.680851 (-250 5600);
DISPLAY INVISIBLE (-250 5600);
FORCEPROP 1 LASTPIN (-600 5575) $PN 1
J 0
(-588 5587);
DISPLAY 0.489362 (-588 5587);
PAINT MONO (-588 5587);
FORCEPROP 1 LASTPIN (-400 5575) $PN 2
J 0
(-438 5587);
DISPLAY 0.489362 (-438 5587);
PAINT MONO (-438 5587);
FORCEPROP 1 LAST VALUE 2.2K
J 2
(-250 5575);
DISPLAY 0.489362 (-250 5575);
PAINT SKYBLUE (-250 5575);
FORCEPROP 2 LAST CDS_LIB pure_quanta
J 0
(-500 5575);
DISPLAY INVISIBLE (-500 5575);
FORCEPROP 1 LAST PATH I396
J 0
(-550 5725);
DISPLAY 0.978723 (-550 5725);
PAINT WHITE (-550 5725);
DISPLAY INVISIBLE (-550 5725);
FORCEPROP 1 LAST WATTAGE 1/16W
J 2
(-525 5425);
DISPLAY 0.978723 (-525 5425);
PAINT SKYBLUE (-525 5425);
DISPLAY INVISIBLE (-525 5425);
FORCEPROP 1 LAST MATERIAL CHIP
J 0
(-500 5425);
DISPLAY 0.978723 (-500 5425);
PAINT SKYBLUE (-500 5425);
DISPLAY INVISIBLE (-500 5425);
FORCEPROP 1 LAST TOLERANCE 5%
J 0
(-500 5475);
DISPLAY 0.978723 (-500 5475);
PAINT SKYBLUE (-500 5475);
DISPLAY INVISIBLE (-500 5475);
FORCEPROP 1 LAST PART_NUMBER CS22202JB07
J 0
(-550 5675);
DISPLAY 0.978723 (-550 5675);
PAINT SKYBLUE (-550 5675);
DISPLAY INVISIBLE (-550 5675);
FORCEPROP 1 LAST PACK_TYPE 0402LF
J 0
(-250 5425);
DISPLAY 0.978723 (-250 5425);
PAINT SKYBLUE (-250 5425);
DISPLAY INVISIBLE (-250 5425);
FORCEADD OFFPAGE..2
R 2
(-1400 5575);
FORCEPROP 2 LAST $XR1 54 
J 0
(-1714 5575);
DISPLAY 0.638298 (-1714 5575);
PAINT MONO (-1714 5575);
FORCEPROP 2 LAST $XR0 81 
J 0
(-1624 5575);
DISPLAY 0.638298 (-1624 5575);
PAINT MONO (-1624 5575);
FORCEPROP 2 LAST CDS_LIB standard
J 0
(-1400 5575);
DISPLAY INVISIBLE (-1400 5575);
FORCEPROP 1 LAST OFFPAGE TRUE
J 2
(-1725 5450);
DISPLAY 0.872340 (-1725 5450);
PAINT GREEN (-1725 5450);
DISPLAY INVISIBLE (-1725 5450);
FORCEPROP 1 LAST COMMENT_BODY TRUE
J 2
(-1355 5480);
DISPLAY 0.872340 (-1355 5480);
PAINT PEACH (-1355 5480);
DISPLAY INVISIBLE (-1355 5480);
FORCEPROP 2 LAST PATH I397
J 0
(-1350 5650);
DISPLAY 0.680851 (-1350 5650);
DISPLAY INVISIBLE (-1350 5650);
FORCEADD Q_RES..1
(-500 5875);
FORCEPROP 1 LAST LOCATION R535
J 0
(-750 5875);
DISPLAY 0.489362 (-750 5875);
PAINT SKYBLUE (-750 5875);
FORCEPROP 0 LAST $SEC 1
J 0
(-250 5900);
DISPLAY 0.680851 (-250 5900);
PAINT MONO (-250 5900);
DISPLAY INVISIBLE (-250 5900);
FORCEPROP 0 LAST CDS_SEC 1
J 0
(-250 5900);
DISPLAY 0.680851 (-250 5900);
DISPLAY INVISIBLE (-250 5900);
FORCEPROP 1 LASTPIN (-600 5875) $PN 1
J 0
(-588 5887);
DISPLAY 0.489362 (-588 5887);
PAINT MONO (-588 5887);
FORCEPROP 1 LASTPIN (-400 5875) $PN 2
J 0
(-438 5887);
DISPLAY 0.489362 (-438 5887);
PAINT MONO (-438 5887);
FORCEPROP 1 LAST VALUE 2.2K
J 2
(-250 5875);
DISPLAY 0.489362 (-250 5875);
PAINT SKYBLUE (-250 5875);
FORCEPROP 2 LAST CDS_LIB pure_quanta
J 0
(-500 5875);
DISPLAY INVISIBLE (-500 5875);
FORCEPROP 1 LAST PATH I398
J 0
(-550 6025);
DISPLAY 0.978723 (-550 6025);
PAINT WHITE (-550 6025);
DISPLAY INVISIBLE (-550 6025);
FORCEPROP 1 LAST WATTAGE 1/16W
J 2
(-525 5725);
DISPLAY 0.978723 (-525 5725);
PAINT SKYBLUE (-525 5725);
DISPLAY INVISIBLE (-525 5725);
FORCEPROP 1 LAST MATERIAL CHIP
J 0
(-500 5725);
DISPLAY 0.978723 (-500 5725);
PAINT SKYBLUE (-500 5725);
DISPLAY INVISIBLE (-500 5725);
FORCEPROP 1 LAST TOLERANCE 5%
J 0
(-500 5775);
DISPLAY 0.978723 (-500 5775);
PAINT SKYBLUE (-500 5775);
DISPLAY INVISIBLE (-500 5775);
FORCEPROP 1 LAST PART_NUMBER CS22202JB07
J 0
(-550 5975);
DISPLAY 0.978723 (-550 5975);
PAINT SKYBLUE (-550 5975);
DISPLAY INVISIBLE (-550 5975);
FORCEPROP 1 LAST PACK_TYPE 0402LF
J 0
(-250 5725);
DISPLAY 0.978723 (-250 5725);
PAINT SKYBLUE (-250 5725);
DISPLAY INVISIBLE (-250 5725);
FORCEADD Q_RES..1
(-500 5825);
FORCEPROP 1 LAST LOCATION R536
J 0
(-750 5825);
DISPLAY 0.489362 (-750 5825);
PAINT SKYBLUE (-750 5825);
FORCEPROP 0 LAST $SEC 1
J 0
(-250 5850);
DISPLAY 0.680851 (-250 5850);
PAINT MONO (-250 5850);
DISPLAY INVISIBLE (-250 5850);
FORCEPROP 0 LAST CDS_SEC 1
J 0
(-250 5850);
DISPLAY 0.680851 (-250 5850);
DISPLAY INVISIBLE (-250 5850);
FORCEPROP 1 LASTPIN (-600 5825) $PN 1
J 0
(-588 5837);
DISPLAY 0.489362 (-588 5837);
PAINT MONO (-588 5837);
FORCEPROP 1 LASTPIN (-400 5825) $PN 2
J 0
(-438 5837);
DISPLAY 0.489362 (-438 5837);
PAINT MONO (-438 5837);
FORCEPROP 1 LAST VALUE 2.2K
J 2
(-250 5825);
DISPLAY 0.489362 (-250 5825);
PAINT SKYBLUE (-250 5825);
FORCEPROP 1 LAST MATERIAL EMPTY
J 0
(-675 5825);
DISPLAY 0.404255 (-675 5825);
PAINT RED (-675 5825);
FORCEPROP 1 LAST PACK_TYPE 0402LF
J 0
(-250 5675);
DISPLAY 0.978723 (-250 5675);
PAINT SKYBLUE (-250 5675);
DISPLAY INVISIBLE (-250 5675);
FORCEPROP 1 LAST PART_NUMBER CS22202JB07
J 0
(-550 5925);
DISPLAY 0.978723 (-550 5925);
PAINT SKYBLUE (-550 5925);
DISPLAY INVISIBLE (-550 5925);
FORCEPROP 1 LAST TOLERANCE 5%
J 0
(-500 5725);
DISPLAY 0.978723 (-500 5725);
PAINT SKYBLUE (-500 5725);
DISPLAY INVISIBLE (-500 5725);
FORCEPROP 1 LAST WATTAGE 1/16W
J 2
(-525 5675);
DISPLAY 0.978723 (-525 5675);
PAINT SKYBLUE (-525 5675);
DISPLAY INVISIBLE (-525 5675);
FORCEPROP 1 LAST PATH I399
J 0
(-550 5975);
DISPLAY 0.978723 (-550 5975);
PAINT WHITE (-550 5975);
DISPLAY INVISIBLE (-550 5975);
FORCEPROP 2 LAST CDS_LIB pure_quanta
J 0
(-500 5825);
DISPLAY INVISIBLE (-500 5825);
FORCEADD Q_RES..1
(-8750 3025);
FORCEPROP 1 LAST LOCATION R512
J 0
(-9000 3025);
DISPLAY 0.489362 (-9000 3025);
PAINT SKYBLUE (-9000 3025);
FORCEPROP 0 LAST $SEC 1
J 0
(-8625 3050);
DISPLAY 0.680851 (-8625 3050);
PAINT MONO (-8625 3050);
DISPLAY INVISIBLE (-8625 3050);
FORCEPROP 0 LAST CDS_SEC 1
J 0
(-8625 3050);
DISPLAY 0.680851 (-8625 3050);
DISPLAY INVISIBLE (-8625 3050);
FORCEPROP 1 LASTPIN (-8850 3025) $PN 1
J 0
(-8838 3037);
DISPLAY 0.489362 (-8838 3037);
PAINT MONO (-8838 3037);
FORCEPROP 1 LASTPIN (-8650 3025) $PN 2
J 0
(-8688 3037);
DISPLAY 0.489362 (-8688 3037);
PAINT MONO (-8688 3037);
FORCEPROP 1 LAST VALUE 2.2K
J 0
(-8625 3025);
DISPLAY 0.489362 (-8625 3025);
PAINT SKYBLUE (-8625 3025);
FORCEPROP 2 LAST CDS_LIB pure_quanta
J 0
(-8750 3025);
DISPLAY INVISIBLE (-8750 3025);
FORCEPROP 1 LAST PATH I400
J 0
(-8800 3175);
DISPLAY 0.978723 (-8800 3175);
PAINT WHITE (-8800 3175);
DISPLAY INVISIBLE (-8800 3175);
FORCEPROP 1 LAST WATTAGE 1/16W
J 2
(-8775 2875);
DISPLAY 0.978723 (-8775 2875);
PAINT SKYBLUE (-8775 2875);
DISPLAY INVISIBLE (-8775 2875);
FORCEPROP 1 LAST MATERIAL CHIP
J 0
(-8750 2875);
DISPLAY 0.978723 (-8750 2875);
PAINT SKYBLUE (-8750 2875);
DISPLAY INVISIBLE (-8750 2875);
FORCEPROP 1 LAST TOLERANCE 5%
J 0
(-8750 2925);
DISPLAY 0.978723 (-8750 2925);
PAINT SKYBLUE (-8750 2925);
DISPLAY INVISIBLE (-8750 2925);
FORCEPROP 1 LAST PART_NUMBER CS22202JB07
J 0
(-8800 3125);
DISPLAY 0.978723 (-8800 3125);
PAINT SKYBLUE (-8800 3125);
DISPLAY INVISIBLE (-8800 3125);
FORCEPROP 1 LAST PACK_TYPE 0402LF
J 0
(-8500 2875);
DISPLAY 0.978723 (-8500 2875);
PAINT SKYBLUE (-8500 2875);
DISPLAY INVISIBLE (-8500 2875);
FORCEADD Q_RES..1
(-8750 3075);
FORCEPROP 1 LAST LOCATION R514
J 0
(-9000 3075);
DISPLAY 0.489362 (-9000 3075);
PAINT SKYBLUE (-9000 3075);
FORCEPROP 0 LAST $SEC 1
J 0
(-8625 3100);
DISPLAY 0.680851 (-8625 3100);
PAINT MONO (-8625 3100);
DISPLAY INVISIBLE (-8625 3100);
FORCEPROP 0 LAST CDS_SEC 1
J 0
(-8625 3100);
DISPLAY 0.680851 (-8625 3100);
DISPLAY INVISIBLE (-8625 3100);
FORCEPROP 1 LASTPIN (-8850 3075) $PN 1
J 0
(-8838 3087);
DISPLAY 0.489362 (-8838 3087);
PAINT MONO (-8838 3087);
FORCEPROP 1 LASTPIN (-8650 3075) $PN 2
J 0
(-8688 3087);
DISPLAY 0.489362 (-8688 3087);
PAINT MONO (-8688 3087);
FORCEPROP 1 LAST VALUE 2.2K
J 0
(-8625 3075);
DISPLAY 0.489362 (-8625 3075);
PAINT SKYBLUE (-8625 3075);
FORCEPROP 2 LAST CDS_LIB pure_quanta
J 0
(-8750 3075);
DISPLAY INVISIBLE (-8750 3075);
FORCEPROP 1 LAST PATH I401
J 0
(-8800 3225);
DISPLAY 0.978723 (-8800 3225);
PAINT WHITE (-8800 3225);
DISPLAY INVISIBLE (-8800 3225);
FORCEPROP 1 LAST WATTAGE 1/16W
J 2
(-8775 2925);
DISPLAY 0.978723 (-8775 2925);
PAINT SKYBLUE (-8775 2925);
DISPLAY INVISIBLE (-8775 2925);
FORCEPROP 1 LAST MATERIAL CHIP
J 0
(-8750 2925);
DISPLAY 0.978723 (-8750 2925);
PAINT SKYBLUE (-8750 2925);
DISPLAY INVISIBLE (-8750 2925);
FORCEPROP 1 LAST TOLERANCE 5%
J 0
(-8750 2975);
DISPLAY 0.978723 (-8750 2975);
PAINT SKYBLUE (-8750 2975);
DISPLAY INVISIBLE (-8750 2975);
FORCEPROP 1 LAST PART_NUMBER CS22202JB07
J 0
(-8800 3175);
DISPLAY 0.978723 (-8800 3175);
PAINT SKYBLUE (-8800 3175);
DISPLAY INVISIBLE (-8800 3175);
FORCEPROP 1 LAST PACK_TYPE 0402LF
J 0
(-8500 2925);
DISPLAY 0.978723 (-8500 2925);
PAINT SKYBLUE (-8500 2925);
DISPLAY INVISIBLE (-8500 2925);
FORCEADD Q_RES..1
(-8750 3125);
FORCEPROP 1 LAST LOCATION R516
J 0
(-9000 3125);
DISPLAY 0.489362 (-9000 3125);
PAINT SKYBLUE (-9000 3125);
FORCEPROP 0 LAST $SEC 1
J 0
(-8625 3150);
DISPLAY 0.680851 (-8625 3150);
PAINT MONO (-8625 3150);
DISPLAY INVISIBLE (-8625 3150);
FORCEPROP 0 LAST CDS_SEC 1
J 0
(-8625 3150);
DISPLAY 0.680851 (-8625 3150);
DISPLAY INVISIBLE (-8625 3150);
FORCEPROP 1 LASTPIN (-8850 3125) $PN 1
J 0
(-8838 3137);
DISPLAY 0.489362 (-8838 3137);
PAINT MONO (-8838 3137);
FORCEPROP 1 LASTPIN (-8650 3125) $PN 2
J 0
(-8688 3137);
DISPLAY 0.489362 (-8688 3137);
PAINT MONO (-8688 3137);
FORCEPROP 1 LAST VALUE 2.2K
J 0
(-8625 3125);
DISPLAY 0.489362 (-8625 3125);
PAINT SKYBLUE (-8625 3125);
FORCEPROP 2 LAST CDS_LIB pure_quanta
J 0
(-8750 3125);
DISPLAY INVISIBLE (-8750 3125);
FORCEPROP 1 LAST PATH I402
J 0
(-8800 3275);
DISPLAY 0.978723 (-8800 3275);
PAINT WHITE (-8800 3275);
DISPLAY INVISIBLE (-8800 3275);
FORCEPROP 1 LAST WATTAGE 1/16W
J 2
(-8775 2975);
DISPLAY 0.978723 (-8775 2975);
PAINT SKYBLUE (-8775 2975);
DISPLAY INVISIBLE (-8775 2975);
FORCEPROP 1 LAST MATERIAL CHIP
J 0
(-8750 2975);
DISPLAY 0.978723 (-8750 2975);
PAINT SKYBLUE (-8750 2975);
DISPLAY INVISIBLE (-8750 2975);
FORCEPROP 1 LAST TOLERANCE 5%
J 0
(-8750 3025);
DISPLAY 0.978723 (-8750 3025);
PAINT SKYBLUE (-8750 3025);
DISPLAY INVISIBLE (-8750 3025);
FORCEPROP 1 LAST PART_NUMBER CS22202JB07
J 0
(-8800 3225);
DISPLAY 0.978723 (-8800 3225);
PAINT SKYBLUE (-8800 3225);
DISPLAY INVISIBLE (-8800 3225);
FORCEPROP 1 LAST PACK_TYPE 0402LF
J 0
(-8500 2975);
DISPLAY 0.978723 (-8500 2975);
PAINT SKYBLUE (-8500 2975);
DISPLAY INVISIBLE (-8500 2975);
FORCEADD Q_RES..2
R 2
(-8750 4825);
FORCEPROP 1 LAST LOCATION R518
J 2
(-8800 4900);
DISPLAY 0.489362 (-8800 4900);
PAINT SKYBLUE (-8800 4900);
FORCEPROP 0 LAST $SEC 1
J 0
(-8800 4925);
DISPLAY 0.680851 (-8800 4925);
PAINT MONO (-8800 4925);
DISPLAY INVISIBLE (-8800 4925);
FORCEPROP 0 LAST CDS_SEC 1
J 0
(-8800 4925);
DISPLAY 0.680851 (-8800 4925);
DISPLAY INVISIBLE (-8800 4925);
FORCEPROP 1 LASTPIN (-8750 4925) $PN 1
J 2
(-8755 4887);
DISPLAY 0.489362 (-8755 4887);
PAINT MONO (-8755 4887);
FORCEPROP 1 LASTPIN (-8750 4725) $PN 2
J 2
(-8755 4735);
DISPLAY 0.489362 (-8755 4735);
PAINT MONO (-8755 4735);
FORCEPROP 1 LAST MATERIAL CHIP
J 2
(-8800 4800);
DISPLAY 0.489362 (-8800 4800);
PAINT SKYBLUE (-8800 4800);
FORCEPROP 1 LAST VALUE 2.2K
J 2
(-8800 4850);
DISPLAY 0.489362 (-8800 4850);
PAINT SKYBLUE (-8800 4850);
FORCEPROP 1 LAST PACK_TYPE 0402LF
J 2
(-8800 4750);
DISPLAY 0.489362 (-8800 4750);
PAINT SKYBLUE (-8800 4750);
FORCEPROP 2 LAST CDS_LIB pure_quanta
J 2
(-8750 4825);
DISPLAY INVISIBLE (-8750 4825);
FORCEPROP 1 LAST PATH I403
J 2
(-8800 5000);
DISPLAY 0.978723 (-8800 5000);
PAINT WHITE (-8800 5000);
DISPLAY INVISIBLE (-8800 5000);
FORCEPROP 1 LAST WATTAGE 1/16W
J 2
(-8790 4800);
DISPLAY 0.510638 (-8790 4800);
PAINT SKYBLUE (-8790 4800);
DISPLAY INVISIBLE (-8790 4800);
FORCEPROP 1 LAST TOLERANCE 5%
J 2
(-8795 4850);
DISPLAY 0.510638 (-8795 4850);
PAINT SKYBLUE (-8795 4850);
DISPLAY INVISIBLE (-8795 4850);
FORCEPROP 1 LAST PART_NUMBER CS22202JB07
J 2
(-8790 4700);
DISPLAY 0.510638 (-8790 4700);
PAINT SKYBLUE (-8790 4700);
DISPLAY INVISIBLE (-8790 4700);
FORCEADD Q_RES..2
R 2
(-8750 4475);
FORCEPROP 1 LAST LOCATION R519
J 2
(-8800 4550);
DISPLAY 0.489362 (-8800 4550);
PAINT SKYBLUE (-8800 4550);
FORCEPROP 0 LAST $SEC 1
J 0
(-8800 4575);
DISPLAY 0.680851 (-8800 4575);
PAINT MONO (-8800 4575);
DISPLAY INVISIBLE (-8800 4575);
FORCEPROP 0 LAST CDS_SEC 1
J 0
(-8800 4575);
DISPLAY 0.680851 (-8800 4575);
DISPLAY INVISIBLE (-8800 4575);
FORCEPROP 1 LASTPIN (-8750 4575) $PN 1
J 2
(-8755 4537);
DISPLAY 0.489362 (-8755 4537);
PAINT MONO (-8755 4537);
FORCEPROP 1 LASTPIN (-8750 4375) $PN 2
J 2
(-8755 4385);
DISPLAY 0.489362 (-8755 4385);
PAINT MONO (-8755 4385);
FORCEPROP 1 LAST MATERIAL EMPTY
J 2
(-8800 4450);
DISPLAY 0.489362 (-8800 4450);
PAINT RED (-8800 4450);
FORCEPROP 1 LAST VALUE 2.2K
J 2
(-8800 4500);
DISPLAY 0.489362 (-8800 4500);
PAINT SKYBLUE (-8800 4500);
FORCEPROP 1 LAST PACK_TYPE 0402LF
J 2
(-8800 4400);
DISPLAY 0.489362 (-8800 4400);
PAINT SKYBLUE (-8800 4400);
FORCEPROP 2 LAST CDS_LIB pure_quanta
J 0
(-8750 4475);
DISPLAY INVISIBLE (-8750 4475);
FORCEPROP 1 LAST PATH I404
J 2
(-8800 4650);
DISPLAY 0.978723 (-8800 4650);
PAINT WHITE (-8800 4650);
DISPLAY INVISIBLE (-8800 4650);
FORCEPROP 1 LAST WATTAGE 1/16W
J 2
(-8790 4450);
DISPLAY 0.510638 (-8790 4450);
PAINT SKYBLUE (-8790 4450);
DISPLAY INVISIBLE (-8790 4450);
FORCEPROP 1 LAST TOLERANCE 5%
J 2
(-8795 4500);
DISPLAY 0.510638 (-8795 4500);
PAINT SKYBLUE (-8795 4500);
DISPLAY INVISIBLE (-8795 4500);
FORCEPROP 1 LAST PART_NUMBER CS22202JB07
J 2
(-8790 4350);
DISPLAY 0.510638 (-8790 4350);
PAINT SKYBLUE (-8790 4350);
DISPLAY INVISIBLE (-8790 4350);
FORCEADD Q_RES..2
(-8625 4475);
FORCEPROP 1 LAST LOCATION R521
J 0
(-8575 4550);
DISPLAY 0.489362 (-8575 4550);
PAINT SKYBLUE (-8575 4550);
FORCEPROP 0 LAST $SEC 1
J 0
(-8575 4575);
DISPLAY 0.680851 (-8575 4575);
PAINT MONO (-8575 4575);
DISPLAY INVISIBLE (-8575 4575);
FORCEPROP 0 LAST CDS_SEC 1
J 0
(-8575 4575);
DISPLAY 0.680851 (-8575 4575);
DISPLAY INVISIBLE (-8575 4575);
FORCEPROP 1 LASTPIN (-8625 4575) $PN 1
J 0
(-8620 4537);
DISPLAY 0.489362 (-8620 4537);
PAINT MONO (-8620 4537);
FORCEPROP 1 LASTPIN (-8625 4375) $PN 2
J 0
(-8620 4385);
DISPLAY 0.489362 (-8620 4385);
PAINT MONO (-8620 4385);
FORCEPROP 1 LAST MATERIAL CHIP
J 0
(-8575 4450);
DISPLAY 0.489362 (-8575 4450);
PAINT SKYBLUE (-8575 4450);
FORCEPROP 1 LAST VALUE 2.2K
J 0
(-8575 4500);
DISPLAY 0.489362 (-8575 4500);
PAINT SKYBLUE (-8575 4500);
FORCEPROP 1 LAST PACK_TYPE 0402LF
J 0
(-8575 4400);
DISPLAY 0.489362 (-8575 4400);
PAINT SKYBLUE (-8575 4400);
FORCEPROP 2 LAST CDS_LIB pure_quanta
J 2
(-8625 4475);
DISPLAY INVISIBLE (-8625 4475);
FORCEPROP 1 LAST PATH I405
J 0
(-8575 4650);
DISPLAY 0.978723 (-8575 4650);
PAINT WHITE (-8575 4650);
DISPLAY INVISIBLE (-8575 4650);
FORCEPROP 1 LAST WATTAGE 1/16W
J 0
(-8585 4450);
DISPLAY 0.510638 (-8585 4450);
PAINT SKYBLUE (-8585 4450);
DISPLAY INVISIBLE (-8585 4450);
FORCEPROP 1 LAST TOLERANCE 5%
J 0
(-8580 4500);
DISPLAY 0.510638 (-8580 4500);
PAINT SKYBLUE (-8580 4500);
DISPLAY INVISIBLE (-8580 4500);
FORCEPROP 1 LAST PART_NUMBER CS22202JB07
J 0
(-8585 4350);
DISPLAY 0.510638 (-8585 4350);
PAINT SKYBLUE (-8585 4350);
DISPLAY INVISIBLE (-8585 4350);
FORCEADD Q_RES..1
(-500 6075);
FORCEPROP 1 LAST LOCATION R531
J 0
(-750 6075);
DISPLAY 0.489362 (-750 6075);
PAINT SKYBLUE (-750 6075);
FORCEPROP 0 LAST $SEC 1
J 0
(-250 6100);
DISPLAY 0.680851 (-250 6100);
PAINT MONO (-250 6100);
DISPLAY INVISIBLE (-250 6100);
FORCEPROP 0 LAST CDS_SEC 1
J 0
(-250 6100);
DISPLAY 0.680851 (-250 6100);
DISPLAY INVISIBLE (-250 6100);
FORCEPROP 1 LASTPIN (-600 6075) $PN 1
J 0
(-588 6087);
DISPLAY 0.489362 (-588 6087);
PAINT MONO (-588 6087);
FORCEPROP 1 LASTPIN (-400 6075) $PN 2
J 0
(-438 6087);
DISPLAY 0.489362 (-438 6087);
PAINT MONO (-438 6087);
FORCEPROP 1 LAST VALUE 2.2K
J 2
(-250 6075);
DISPLAY 0.489362 (-250 6075);
PAINT SKYBLUE (-250 6075);
FORCEPROP 2 LAST CDS_LIB pure_quanta
J 0
(-500 6075);
DISPLAY INVISIBLE (-500 6075);
FORCEPROP 1 LAST PATH I406
J 0
(-550 6225);
DISPLAY 0.978723 (-550 6225);
PAINT WHITE (-550 6225);
DISPLAY INVISIBLE (-550 6225);
FORCEPROP 1 LAST WATTAGE 1/16W
J 2
(-525 5925);
DISPLAY 0.978723 (-525 5925);
PAINT SKYBLUE (-525 5925);
DISPLAY INVISIBLE (-525 5925);
FORCEPROP 1 LAST MATERIAL CHIP
J 0
(-500 5925);
DISPLAY 0.978723 (-500 5925);
PAINT SKYBLUE (-500 5925);
DISPLAY INVISIBLE (-500 5925);
FORCEPROP 1 LAST TOLERANCE 5%
J 0
(-500 5975);
DISPLAY 0.978723 (-500 5975);
PAINT SKYBLUE (-500 5975);
DISPLAY INVISIBLE (-500 5975);
FORCEPROP 1 LAST PART_NUMBER CS22202JB07
J 0
(-550 6175);
DISPLAY 0.978723 (-550 6175);
PAINT SKYBLUE (-550 6175);
DISPLAY INVISIBLE (-550 6175);
FORCEPROP 1 LAST PACK_TYPE 0402LF
J 0
(-250 5925);
DISPLAY 0.978723 (-250 5925);
PAINT SKYBLUE (-250 5925);
DISPLAY INVISIBLE (-250 5925);
FORCEADD Q_RES..1
(-500 6025);
FORCEPROP 1 LAST LOCATION R532
J 0
(-750 6025);
DISPLAY 0.489362 (-750 6025);
PAINT SKYBLUE (-750 6025);
FORCEPROP 0 LAST $SEC 1
J 0
(-250 6050);
DISPLAY 0.680851 (-250 6050);
PAINT MONO (-250 6050);
DISPLAY INVISIBLE (-250 6050);
FORCEPROP 0 LAST CDS_SEC 1
J 0
(-250 6050);
DISPLAY 0.680851 (-250 6050);
DISPLAY INVISIBLE (-250 6050);
FORCEPROP 1 LASTPIN (-600 6025) $PN 1
J 0
(-588 6037);
DISPLAY 0.489362 (-588 6037);
PAINT MONO (-588 6037);
FORCEPROP 1 LASTPIN (-400 6025) $PN 2
J 0
(-438 6037);
DISPLAY 0.489362 (-438 6037);
PAINT MONO (-438 6037);
FORCEPROP 1 LAST VALUE 2.2K
J 2
(-250 6025);
DISPLAY 0.489362 (-250 6025);
PAINT SKYBLUE (-250 6025);
FORCEPROP 2 LAST CDS_LIB pure_quanta
J 0
(-500 6025);
DISPLAY INVISIBLE (-500 6025);
FORCEPROP 1 LAST PATH I407
J 0
(-550 6175);
DISPLAY 0.978723 (-550 6175);
PAINT WHITE (-550 6175);
DISPLAY INVISIBLE (-550 6175);
FORCEPROP 1 LAST WATTAGE 1/16W
J 2
(-525 5875);
DISPLAY 0.978723 (-525 5875);
PAINT SKYBLUE (-525 5875);
DISPLAY INVISIBLE (-525 5875);
FORCEPROP 1 LAST MATERIAL CHIP
J 0
(-500 5875);
DISPLAY 0.978723 (-500 5875);
PAINT SKYBLUE (-500 5875);
DISPLAY INVISIBLE (-500 5875);
FORCEPROP 1 LAST TOLERANCE 5%
J 0
(-500 5925);
DISPLAY 0.978723 (-500 5925);
PAINT SKYBLUE (-500 5925);
DISPLAY INVISIBLE (-500 5925);
FORCEPROP 1 LAST PART_NUMBER CS22202JB07
J 0
(-550 6125);
DISPLAY 0.978723 (-550 6125);
PAINT SKYBLUE (-550 6125);
DISPLAY INVISIBLE (-550 6125);
FORCEPROP 1 LAST PACK_TYPE 0402LF
J 0
(-250 5875);
DISPLAY 0.978723 (-250 5875);
PAINT SKYBLUE (-250 5875);
DISPLAY INVISIBLE (-250 5875);
FORCEADD Q_RES..1
(-500 5975);
FORCEPROP 1 LAST LOCATION R533
J 0
(-750 5975);
DISPLAY 0.489362 (-750 5975);
PAINT SKYBLUE (-750 5975);
FORCEPROP 0 LAST $SEC 1
J 0
(-250 6000);
DISPLAY 0.680851 (-250 6000);
PAINT MONO (-250 6000);
DISPLAY INVISIBLE (-250 6000);
FORCEPROP 0 LAST CDS_SEC 1
J 0
(-250 6000);
DISPLAY 0.680851 (-250 6000);
DISPLAY INVISIBLE (-250 6000);
FORCEPROP 1 LASTPIN (-600 5975) $PN 1
J 0
(-588 5987);
DISPLAY 0.489362 (-588 5987);
PAINT MONO (-588 5987);
FORCEPROP 1 LASTPIN (-400 5975) $PN 2
J 0
(-438 5987);
DISPLAY 0.489362 (-438 5987);
PAINT MONO (-438 5987);
FORCEPROP 1 LAST VALUE 2.2K
J 2
(-250 5975);
DISPLAY 0.489362 (-250 5975);
PAINT SKYBLUE (-250 5975);
FORCEPROP 2 LAST CDS_LIB pure_quanta
J 0
(-500 5975);
DISPLAY INVISIBLE (-500 5975);
FORCEPROP 1 LAST PATH I408
J 0
(-550 6125);
DISPLAY 0.978723 (-550 6125);
PAINT WHITE (-550 6125);
DISPLAY INVISIBLE (-550 6125);
FORCEPROP 1 LAST WATTAGE 1/16W
J 2
(-525 5825);
DISPLAY 0.978723 (-525 5825);
PAINT SKYBLUE (-525 5825);
DISPLAY INVISIBLE (-525 5825);
FORCEPROP 1 LAST MATERIAL CHIP
J 0
(-500 5825);
DISPLAY 0.978723 (-500 5825);
PAINT SKYBLUE (-500 5825);
DISPLAY INVISIBLE (-500 5825);
FORCEPROP 1 LAST TOLERANCE 5%
J 0
(-500 5875);
DISPLAY 0.978723 (-500 5875);
PAINT SKYBLUE (-500 5875);
DISPLAY INVISIBLE (-500 5875);
FORCEPROP 1 LAST PART_NUMBER CS22202JB07
J 0
(-550 6075);
DISPLAY 0.978723 (-550 6075);
PAINT SKYBLUE (-550 6075);
DISPLAY INVISIBLE (-550 6075);
FORCEPROP 1 LAST PACK_TYPE 0402LF
J 0
(-250 5825);
DISPLAY 0.978723 (-250 5825);
PAINT SKYBLUE (-250 5825);
DISPLAY INVISIBLE (-250 5825);
FORCEADD Q_RES..1
(-500 5925);
FORCEPROP 1 LAST LOCATION R534
J 0
(-750 5925);
DISPLAY 0.489362 (-750 5925);
PAINT SKYBLUE (-750 5925);
FORCEPROP 0 LAST $SEC 1
J 0
(-250 5950);
DISPLAY 0.680851 (-250 5950);
PAINT MONO (-250 5950);
DISPLAY INVISIBLE (-250 5950);
FORCEPROP 0 LAST CDS_SEC 1
J 0
(-250 5950);
DISPLAY 0.680851 (-250 5950);
DISPLAY INVISIBLE (-250 5950);
FORCEPROP 1 LASTPIN (-600 5925) $PN 1
J 0
(-588 5937);
DISPLAY 0.489362 (-588 5937);
PAINT MONO (-588 5937);
FORCEPROP 1 LASTPIN (-400 5925) $PN 2
J 0
(-438 5937);
DISPLAY 0.489362 (-438 5937);
PAINT MONO (-438 5937);
FORCEPROP 1 LAST VALUE 2.2K
J 2
(-250 5925);
DISPLAY 0.489362 (-250 5925);
PAINT SKYBLUE (-250 5925);
FORCEPROP 2 LAST CDS_LIB pure_quanta
J 0
(-500 5925);
DISPLAY INVISIBLE (-500 5925);
FORCEPROP 1 LAST PATH I409
J 0
(-550 6075);
DISPLAY 0.978723 (-550 6075);
PAINT WHITE (-550 6075);
DISPLAY INVISIBLE (-550 6075);
FORCEPROP 1 LAST WATTAGE 1/16W
J 2
(-525 5775);
DISPLAY 0.978723 (-525 5775);
PAINT SKYBLUE (-525 5775);
DISPLAY INVISIBLE (-525 5775);
FORCEPROP 1 LAST MATERIAL CHIP
J 0
(-500 5775);
DISPLAY 0.978723 (-500 5775);
PAINT SKYBLUE (-500 5775);
DISPLAY INVISIBLE (-500 5775);
FORCEPROP 1 LAST TOLERANCE 5%
J 0
(-500 5825);
DISPLAY 0.978723 (-500 5825);
PAINT SKYBLUE (-500 5825);
DISPLAY INVISIBLE (-500 5825);
FORCEPROP 1 LAST PART_NUMBER CS22202JB07
J 0
(-550 6025);
DISPLAY 0.978723 (-550 6025);
PAINT SKYBLUE (-550 6025);
DISPLAY INVISIBLE (-550 6025);
FORCEPROP 1 LAST PACK_TYPE 0402LF
J 0
(-250 5775);
DISPLAY 0.978723 (-250 5775);
PAINT SKYBLUE (-250 5775);
DISPLAY INVISIBLE (-250 5775);
FORCEADD Q_RES..1
(-500 5775);
FORCEPROP 1 LAST LOCATION R537
J 0
(-750 5775);
DISPLAY 0.489362 (-750 5775);
PAINT SKYBLUE (-750 5775);
FORCEPROP 0 LAST $SEC 1
J 0
(-250 5800);
DISPLAY 0.680851 (-250 5800);
PAINT MONO (-250 5800);
DISPLAY INVISIBLE (-250 5800);
FORCEPROP 0 LAST CDS_SEC 1
J 0
(-250 5800);
DISPLAY 0.680851 (-250 5800);
DISPLAY INVISIBLE (-250 5800);
FORCEPROP 1 LASTPIN (-600 5775) $PN 1
J 0
(-588 5787);
DISPLAY 0.489362 (-588 5787);
PAINT MONO (-588 5787);
FORCEPROP 1 LASTPIN (-400 5775) $PN 2
J 0
(-438 5787);
DISPLAY 0.489362 (-438 5787);
PAINT MONO (-438 5787);
FORCEPROP 1 LAST VALUE 2.2K
J 2
(-250 5775);
DISPLAY 0.489362 (-250 5775);
PAINT SKYBLUE (-250 5775);
FORCEPROP 2 LAST CDS_LIB pure_quanta
J 0
(-500 5775);
DISPLAY INVISIBLE (-500 5775);
FORCEPROP 1 LAST PATH I410
J 0
(-550 5925);
DISPLAY 0.978723 (-550 5925);
PAINT WHITE (-550 5925);
DISPLAY INVISIBLE (-550 5925);
FORCEPROP 1 LAST WATTAGE 1/16W
J 2
(-525 5625);
DISPLAY 0.978723 (-525 5625);
PAINT SKYBLUE (-525 5625);
DISPLAY INVISIBLE (-525 5625);
FORCEPROP 1 LAST MATERIAL CHIP
J 0
(-500 5625);
DISPLAY 0.978723 (-500 5625);
PAINT SKYBLUE (-500 5625);
DISPLAY INVISIBLE (-500 5625);
FORCEPROP 1 LAST TOLERANCE 5%
J 0
(-500 5675);
DISPLAY 0.978723 (-500 5675);
PAINT SKYBLUE (-500 5675);
DISPLAY INVISIBLE (-500 5675);
FORCEPROP 1 LAST PART_NUMBER CS22202JB07
J 0
(-550 5875);
DISPLAY 0.978723 (-550 5875);
PAINT SKYBLUE (-550 5875);
DISPLAY INVISIBLE (-550 5875);
FORCEPROP 1 LAST PACK_TYPE 0402LF
J 0
(-250 5625);
DISPLAY 0.978723 (-250 5625);
PAINT SKYBLUE (-250 5625);
DISPLAY INVISIBLE (-250 5625);
FORCEADD Q_RES..1
(-500 5725);
FORCEPROP 1 LAST LOCATION R538
J 0
(-750 5725);
DISPLAY 0.489362 (-750 5725);
PAINT SKYBLUE (-750 5725);
FORCEPROP 0 LAST $SEC 1
J 0
(-250 5750);
DISPLAY 0.680851 (-250 5750);
PAINT MONO (-250 5750);
DISPLAY INVISIBLE (-250 5750);
FORCEPROP 0 LAST CDS_SEC 1
J 0
(-250 5750);
DISPLAY 0.680851 (-250 5750);
DISPLAY INVISIBLE (-250 5750);
FORCEPROP 1 LASTPIN (-600 5725) $PN 1
J 0
(-588 5737);
DISPLAY 0.489362 (-588 5737);
PAINT MONO (-588 5737);
FORCEPROP 1 LASTPIN (-400 5725) $PN 2
J 0
(-438 5737);
DISPLAY 0.489362 (-438 5737);
PAINT MONO (-438 5737);
FORCEPROP 1 LAST VALUE 2.2K
J 2
(-250 5725);
DISPLAY 0.489362 (-250 5725);
PAINT SKYBLUE (-250 5725);
FORCEPROP 2 LAST CDS_LIB pure_quanta
J 0
(-500 5725);
DISPLAY INVISIBLE (-500 5725);
FORCEPROP 1 LAST PATH I411
J 0
(-550 5875);
DISPLAY 0.978723 (-550 5875);
PAINT WHITE (-550 5875);
DISPLAY INVISIBLE (-550 5875);
FORCEPROP 1 LAST WATTAGE 1/16W
J 2
(-525 5575);
DISPLAY 0.978723 (-525 5575);
PAINT SKYBLUE (-525 5575);
DISPLAY INVISIBLE (-525 5575);
FORCEPROP 1 LAST MATERIAL CHIP
J 0
(-500 5575);
DISPLAY 0.978723 (-500 5575);
PAINT SKYBLUE (-500 5575);
DISPLAY INVISIBLE (-500 5575);
FORCEPROP 1 LAST TOLERANCE 5%
J 0
(-500 5625);
DISPLAY 0.978723 (-500 5625);
PAINT SKYBLUE (-500 5625);
DISPLAY INVISIBLE (-500 5625);
FORCEPROP 1 LAST PART_NUMBER CS22202JB07
J 0
(-550 5825);
DISPLAY 0.978723 (-550 5825);
PAINT SKYBLUE (-550 5825);
DISPLAY INVISIBLE (-550 5825);
FORCEPROP 1 LAST PACK_TYPE 0402LF
J 0
(-250 5575);
DISPLAY 0.978723 (-250 5575);
PAINT SKYBLUE (-250 5575);
DISPLAY INVISIBLE (-250 5575);
FORCEADD Q_RES..1
(-500 5675);
FORCEPROP 1 LAST LOCATION R539
J 0
(-750 5675);
DISPLAY 0.489362 (-750 5675);
PAINT SKYBLUE (-750 5675);
FORCEPROP 0 LAST $SEC 1
J 0
(-250 5700);
DISPLAY 0.680851 (-250 5700);
PAINT MONO (-250 5700);
DISPLAY INVISIBLE (-250 5700);
FORCEPROP 0 LAST CDS_SEC 1
J 0
(-250 5700);
DISPLAY 0.680851 (-250 5700);
DISPLAY INVISIBLE (-250 5700);
FORCEPROP 1 LASTPIN (-600 5675) $PN 1
J 0
(-588 5687);
DISPLAY 0.489362 (-588 5687);
PAINT MONO (-588 5687);
FORCEPROP 1 LASTPIN (-400 5675) $PN 2
J 0
(-438 5687);
DISPLAY 0.489362 (-438 5687);
PAINT MONO (-438 5687);
FORCEPROP 1 LAST VALUE 2.2K
J 2
(-250 5675);
DISPLAY 0.489362 (-250 5675);
PAINT SKYBLUE (-250 5675);
FORCEPROP 2 LAST CDS_LIB pure_quanta
J 0
(-500 5675);
DISPLAY INVISIBLE (-500 5675);
FORCEPROP 1 LAST PATH I412
J 0
(-550 5825);
DISPLAY 0.978723 (-550 5825);
PAINT WHITE (-550 5825);
DISPLAY INVISIBLE (-550 5825);
FORCEPROP 1 LAST WATTAGE 1/16W
J 2
(-525 5525);
DISPLAY 0.978723 (-525 5525);
PAINT SKYBLUE (-525 5525);
DISPLAY INVISIBLE (-525 5525);
FORCEPROP 1 LAST MATERIAL CHIP
J 0
(-500 5525);
DISPLAY 0.978723 (-500 5525);
PAINT SKYBLUE (-500 5525);
DISPLAY INVISIBLE (-500 5525);
FORCEPROP 1 LAST TOLERANCE 5%
J 0
(-500 5575);
DISPLAY 0.978723 (-500 5575);
PAINT SKYBLUE (-500 5575);
DISPLAY INVISIBLE (-500 5575);
FORCEPROP 1 LAST PART_NUMBER CS22202JB07
J 0
(-550 5775);
DISPLAY 0.978723 (-550 5775);
PAINT SKYBLUE (-550 5775);
DISPLAY INVISIBLE (-550 5775);
FORCEPROP 1 LAST PACK_TYPE 0402LF
J 0
(-250 5525);
DISPLAY 0.978723 (-250 5525);
PAINT SKYBLUE (-250 5525);
DISPLAY INVISIBLE (-250 5525);
FORCEADD Q_RES..1
(-500 5625);
FORCEPROP 1 LAST LOCATION R540
J 0
(-750 5625);
DISPLAY 0.489362 (-750 5625);
PAINT SKYBLUE (-750 5625);
FORCEPROP 0 LAST $SEC 1
J 0
(-250 5650);
DISPLAY 0.680851 (-250 5650);
PAINT MONO (-250 5650);
DISPLAY INVISIBLE (-250 5650);
FORCEPROP 0 LAST CDS_SEC 1
J 0
(-250 5650);
DISPLAY 0.680851 (-250 5650);
DISPLAY INVISIBLE (-250 5650);
FORCEPROP 1 LASTPIN (-600 5625) $PN 1
J 0
(-588 5637);
DISPLAY 0.489362 (-588 5637);
PAINT MONO (-588 5637);
FORCEPROP 1 LASTPIN (-400 5625) $PN 2
J 0
(-438 5637);
DISPLAY 0.489362 (-438 5637);
PAINT MONO (-438 5637);
FORCEPROP 1 LAST VALUE 2.2K
J 2
(-250 5625);
DISPLAY 0.489362 (-250 5625);
PAINT SKYBLUE (-250 5625);
FORCEPROP 2 LAST CDS_LIB pure_quanta
J 0
(-500 5625);
DISPLAY INVISIBLE (-500 5625);
FORCEPROP 1 LAST PATH I413
J 0
(-550 5775);
DISPLAY 0.978723 (-550 5775);
PAINT WHITE (-550 5775);
DISPLAY INVISIBLE (-550 5775);
FORCEPROP 1 LAST WATTAGE 1/16W
J 2
(-525 5475);
DISPLAY 0.978723 (-525 5475);
PAINT SKYBLUE (-525 5475);
DISPLAY INVISIBLE (-525 5475);
FORCEPROP 1 LAST MATERIAL CHIP
J 0
(-500 5475);
DISPLAY 0.978723 (-500 5475);
PAINT SKYBLUE (-500 5475);
DISPLAY INVISIBLE (-500 5475);
FORCEPROP 1 LAST TOLERANCE 5%
J 0
(-500 5525);
DISPLAY 0.978723 (-500 5525);
PAINT SKYBLUE (-500 5525);
DISPLAY INVISIBLE (-500 5525);
FORCEPROP 1 LAST PART_NUMBER CS22202JB07
J 0
(-550 5725);
DISPLAY 0.978723 (-550 5725);
PAINT SKYBLUE (-550 5725);
DISPLAY INVISIBLE (-550 5725);
FORCEPROP 1 LAST PACK_TYPE 0402LF
J 0
(-250 5475);
DISPLAY 0.978723 (-250 5475);
PAINT SKYBLUE (-250 5475);
DISPLAY INVISIBLE (-250 5475);
FORCEADD OFFPAGE..2
(-2375 4975);
FORCEPROP 2 LAST $XR1 81 
J 0
(-2096 4975);
DISPLAY 0.638298 (-2096 4975);
PAINT MONO (-2096 4975);
FORCEPROP 2 LAST $XR0 27 
J 0
(-2186 4975);
DISPLAY 0.638298 (-2186 4975);
PAINT MONO (-2186 4975);
FORCEPROP 1 LAST COMMENT_BODY TRUE
J 0
(-2420 4880);
DISPLAY 0.872340 (-2420 4880);
PAINT GREEN (-2420 4880);
DISPLAY INVISIBLE (-2420 4880);
FORCEPROP 1 LAST OFFPAGE TRUE
J 0
(-2050 4850);
DISPLAY 0.872340 (-2050 4850);
PAINT GREEN (-2050 4850);
DISPLAY INVISIBLE (-2050 4850);
FORCEPROP 2 LAST CDS_LIB standard
J 2
(-2375 4975);
DISPLAY INVISIBLE (-2375 4975);
FORCEPROP 2 LAST PATH I414
J 0
(-2075 5025);
DISPLAY 0.680851 (-2075 5025);
DISPLAY INVISIBLE (-2075 5025);
FORCEADD Q_RES..1
(-3100 4975);
FORCEPROP 1 LAST LOCATION R488
J 0
(-2975 4975);
DISPLAY 0.489362 (-2975 4975);
PAINT SKYBLUE (-2975 4975);
FORCEPROP 2 LAST $SEC 1
J 0
(-3150 5175);
DISPLAY 0.680851 (-3150 5175);
PAINT MONO (-3150 5175);
DISPLAY INVISIBLE (-3150 5175);
FORCEPROP 2 LAST CDS_SEC 1
J 0
(-3150 5175);
DISPLAY 0.680851 (-3150 5175);
DISPLAY INVISIBLE (-3150 5175);
FORCEPROP 1 LASTPIN (-3200 4975) $PN 1
J 0
(-3188 4987);
DISPLAY 0.489362 (-3188 4987);
PAINT MONO (-3188 4987);
FORCEPROP 1 LASTPIN (-3000 4975) $PN 2
J 0
(-3038 4987);
DISPLAY 0.489362 (-3038 4987);
PAINT MONO (-3038 4987);
FORCEPROP 1 LAST VALUE 33
J 2
(-3225 4975);
DISPLAY 0.489362 (-3225 4975);
PAINT SKYBLUE (-3225 4975);
FORCEPROP 2 LAST BOM_COST MEM
J 2
(-3075 5125);
DISPLAY 0.744681 (-3075 5125);
PAINT WHITE (-3075 5125);
DISPLAY INVISIBLE (-3075 5125);
FORCEPROP 2 LAST CDS_LIB pure_quanta
J 0
(-3100 4975);
DISPLAY INVISIBLE (-3100 4975);
FORCEPROP 1 LAST PATH I415
J 0
(-3150 5125);
DISPLAY 0.978723 (-3150 5125);
PAINT WHITE (-3150 5125);
DISPLAY INVISIBLE (-3150 5125);
FORCEPROP 1 LAST WATTAGE 1/16W
J 2
(-3175 4900);
DISPLAY 0.489362 (-3175 4900);
PAINT SKYBLUE (-3175 4900);
DISPLAY INVISIBLE (-3175 4900);
FORCEPROP 1 LAST MATERIAL CHIP
J 2
(-2925 4950);
DISPLAY 0.489362 (-2925 4950);
PAINT SKYBLUE (-2925 4950);
DISPLAY INVISIBLE (-2925 4950);
FORCEPROP 1 LAST TOLERANCE 5%
J 0
(-3225 4950);
DISPLAY 0.489362 (-3225 4950);
PAINT SKYBLUE (-3225 4950);
DISPLAY INVISIBLE (-3225 4950);
FORCEPROP 1 LAST PART_NUMBER CS03302JB29
J 2
(-3000 5025);
DISPLAY 0.489362 (-3000 5025);
PAINT SKYBLUE (-3000 5025);
DISPLAY INVISIBLE (-3000 5025);
FORCEPROP 1 LAST PACK_TYPE 0402LF
J 2
(-2925 4900);
DISPLAY 0.489362 (-2925 4900);
PAINT SKYBLUE (-2925 4900);
DISPLAY INVISIBLE (-2925 4900);
FORCEPROP 2 LAST ROOM RST_CPU0_PLD_TO_DIMM
J 2
(-3075 5075);
DISPLAY 0.744681 (-3075 5075);
PAINT RED (-3075 5075);
DISPLAY INVISIBLE (-3075 5075);
FORCEADD OFFPAGE..2
(-2350 5125);
FORCEPROP 2 LAST $XR0 80 
J 0
(-2161 5125);
DISPLAY 0.638298 (-2161 5125);
PAINT MONO (-2161 5125);
FORCEPROP 2 LAST PATH I416
J 0
(-2050 5175);
DISPLAY 0.680851 (-2050 5175);
DISPLAY INVISIBLE (-2050 5175);
FORCEPROP 2 LAST CDS_LIB standard
J 2
(-2350 5125);
DISPLAY INVISIBLE (-2350 5125);
FORCEPROP 1 LAST OFFPAGE TRUE
J 0
(-2025 5000);
DISPLAY 0.872340 (-2025 5000);
PAINT GREEN (-2025 5000);
DISPLAY INVISIBLE (-2025 5000);
FORCEPROP 1 LAST COMMENT_BODY TRUE
J 0
(-2395 5030);
DISPLAY 0.872340 (-2395 5030);
PAINT GREEN (-2395 5030);
DISPLAY INVISIBLE (-2395 5030);
FORCEADD Q_RES..1
(-3100 5125);
FORCEPROP 1 LAST LOCATION R497
J 0
(-2975 5125);
DISPLAY 0.489362 (-2975 5125);
PAINT SKYBLUE (-2975 5125);
FORCEPROP 0 LAST $SEC 1
J 0
(-2975 5175);
DISPLAY 0.680851 (-2975 5175);
PAINT MONO (-2975 5175);
DISPLAY INVISIBLE (-2975 5175);
FORCEPROP 0 LAST CDS_SEC 1
J 0
(-2975 5175);
DISPLAY 1.021277 (-2975 5175);
DISPLAY INVISIBLE (-2975 5175);
FORCEPROP 1 LASTPIN (-3200 5125) $PN 1
J 0
(-3188 5137);
DISPLAY 0.489362 (-3188 5137);
PAINT MONO (-3188 5137);
FORCEPROP 1 LASTPIN (-3000 5125) $PN 2
J 0
(-3038 5137);
DISPLAY 0.489362 (-3038 5137);
PAINT MONO (-3038 5137);
FORCEPROP 1 LAST VALUE 33
J 2
(-3225 5125);
DISPLAY 0.489362 (-3225 5125);
PAINT SKYBLUE (-3225 5125);
FORCEPROP 2 LAST BOM_COST MEM
J 2
(-3075 5275);
DISPLAY 0.744681 (-3075 5275);
PAINT WHITE (-3075 5275);
DISPLAY INVISIBLE (-3075 5275);
FORCEPROP 2 LAST CDS_LIB pure_quanta
J 0
(-3100 5125);
DISPLAY INVISIBLE (-3100 5125);
FORCEPROP 1 LAST PATH I417
J 0
(-3150 5275);
DISPLAY 0.978723 (-3150 5275);
PAINT WHITE (-3150 5275);
DISPLAY INVISIBLE (-3150 5275);
FORCEPROP 1 LAST WATTAGE 1/16W
J 2
(-3175 5050);
DISPLAY 0.489362 (-3175 5050);
PAINT SKYBLUE (-3175 5050);
DISPLAY INVISIBLE (-3175 5050);
FORCEPROP 1 LAST MATERIAL CHIP
J 2
(-2925 5100);
DISPLAY 0.489362 (-2925 5100);
PAINT SKYBLUE (-2925 5100);
DISPLAY INVISIBLE (-2925 5100);
FORCEPROP 1 LAST TOLERANCE 5%
J 0
(-3225 5100);
DISPLAY 0.489362 (-3225 5100);
PAINT SKYBLUE (-3225 5100);
DISPLAY INVISIBLE (-3225 5100);
FORCEPROP 1 LAST PART_NUMBER CS03302JB29
J 2
(-3000 5175);
DISPLAY 0.489362 (-3000 5175);
PAINT SKYBLUE (-3000 5175);
DISPLAY INVISIBLE (-3000 5175);
FORCEPROP 1 LAST PACK_TYPE 0402LF
J 2
(-2925 5050);
DISPLAY 0.489362 (-2925 5050);
PAINT SKYBLUE (-2925 5050);
DISPLAY INVISIBLE (-2925 5050);
FORCEPROP 2 LAST ROOM RST_CPU0_PLD_TO_DIMM
J 2
(-3075 5225);
DISPLAY 0.744681 (-3075 5225);
PAINT RED (-3075 5225);
DISPLAY INVISIBLE (-3075 5225);
FORCEADD DNS..2
(-7000 600);
PAINT RED (-7000 600);
FORCEPROP 2 LAST CDS_LIB mstr_misc
J 0
(-7000 600);
DISPLAY INVISIBLE (-7000 600);
FORCEPROP 1 LAST COMMENT_BODY TRUE
J 0
(-7000 600);
PAINT RED (-7000 600);
DISPLAY INVISIBLE (-7000 600);
FORCEADD DNS..2
(-7650 600);
PAINT RED (-7650 600);
FORCEPROP 2 LAST CDS_LIB mstr_misc
J 0
(-7650 600);
DISPLAY INVISIBLE (-7650 600);
FORCEPROP 1 LAST COMMENT_BODY TRUE
J 0
(-7650 600);
PAINT RED (-7650 600);
DISPLAY INVISIBLE (-7650 600);
FORCEADD DNS..2
(-7325 600);
PAINT RED (-7325 600);
FORCEPROP 2 LAST CDS_LIB mstr_misc
J 0
(-7325 600);
DISPLAY INVISIBLE (-7325 600);
FORCEPROP 1 LAST COMMENT_BODY TRUE
J 0
(-7325 600);
PAINT RED (-7325 600);
DISPLAY INVISIBLE (-7325 600);
FORCEADD DNS..2
(-8300 600);
PAINT RED (-8300 600);
FORCEPROP 2 LAST CDS_LIB mstr_misc
J 0
(-8300 600);
PAINT MONO (-8300 600);
DISPLAY INVISIBLE (-8300 600);
FORCEPROP 1 LAST COMMENT_BODY TRUE
J 0
(-8300 600);
PAINT RED (-8300 600);
DISPLAY INVISIBLE (-8300 600);
FORCEADD DNS..2
(-6750 600);
PAINT RED (-6750 600);
FORCEPROP 2 LAST CDS_LIB mstr_misc
J 0
(-6750 600);
DISPLAY INVISIBLE (-6750 600);
FORCEPROP 1 LAST COMMENT_BODY TRUE
J 0
(-6750 600);
PAINT RED (-6750 600);
DISPLAY INVISIBLE (-6750 600);
FORCEADD DNS..2
(-8775 4400);
PAINT RED (-8775 4400);
FORCEPROP 2 LAST CDS_LIB mstr_misc
J 0
(-8775 4400);
DISPLAY INVISIBLE (-8775 4400);
FORCEPROP 1 LAST COMMENT_BODY TRUE
J 0
(-8775 4400);
PAINT RED (-8775 4400);
DISPLAY INVISIBLE (-8775 4400);
FORCEADD DNS..2
(-450 5825);
PAINT RED (-450 5825);
FORCEPROP 1 LAST COMMENT_BODY TRUE
J 0
(-450 5825);
PAINT RED (-450 5825);
DISPLAY INVISIBLE (-450 5825);
FORCEPROP 2 LAST CDS_LIB mstr_misc
J 0
(-450 5825);
DISPLAY INVISIBLE (-450 5825);
FORCEADD QUANTA_TITLE_BLOCK_C..1
(0 0);
FORCEPROP 0 LAST CDS_CON_LAST_MODIFIED Fri Mar 11 14:52:38 2022
J 0
(-1885 15);
DISPLAY INVISIBLE (-1885 15);
FORCEPROP 1 LAST CUSTOM_TXT_CDS <CON_LAST_MODIFIED>
J 0
(-1885 15);
DISPLAY 0.978723 (-1885 15);
FORCEPROP 2 LAST CUSTOM_TXT_CDS <XR_PAGE_TITLE>
J 0
(-7890 5250);
DISPLAY 0.638298 (-7890 5250);
PAINT PINK (-7890 5250);
DISPLAY INVISIBLE (-7890 5250);
FORCEPROP 1 LAST CUSTOM_TXT_CDS <NAME_2>
J 0
(-3175 50);
FORCEPROP 1 LAST CUSTOM_TXT_CDS <NAME_1>
J 0
(-3175 175);
FORCEPROP 1 LAST CUSTOM_TXT_CDS <Q_NUMBER>
J 0
(-1403 103);
DISPLAY 1.212766 (-1403 103);
FORCEPROP 1 LAST CUSTOM_TXT_CDS <Q_PROJ>
J 0
(-2382 102);
DISPLAY 1.212766 (-2382 102);
FORCEPROP 1 LAST CUSTOM_TXT_CDS <Q_REV>
J 0
(-184 103);
DISPLAY 1.212766 (-184 103);
FORCEPROP 1 LAST CUSTOM_TXT_CDS <CON_PAGE_NUM> OF <CON_TOTAL_PAGES>
J 0
(-446 18);
DISPLAY 0.978723 (-446 18);
FORCEPROP 1 LAST Q_TITLE CPU1 MISC 1/2
J 0
(-9275 50);
DISPLAY 2.446809 (-9275 50);
PAINT GREEN (-9275 50);
FORCEPROP 1 LAST Q_DEPT BU9
J 1
(-3763 49);
DISPLAY 1.957447 (-3763 49);
PAINT GREEN (-3763 49);
FORCEPROP 2 LAST CDS_LIB pure_quanta
J 0
(0 0);
DISPLAY INVISIBLE (0 0);
FORCEPROP 1 LAST CDS_LMAN_SYM_OUTLINE -9475,6775,100,-125
J 0
(0 0);
DISPLAY 0.468085 (0 0);
PAINT GREEN (0 0);
DISPLAY INVISIBLE (0 0);
FORCEPROP 2 LAST PAGE_BORDER TRUE
J 0
(-7890 5250);
DISPLAY 0.638298 (-7890 5250);
PAINT PINK (-7890 5250);
DISPLAY INVISIBLE (-7890 5250);
FORCEPROP 1 LAST COMMENT_BODY TRUE
J 0
(12 -13);
DISPLAY 0.978723 (12 -13);
PAINT GREEN (12 -13);
DISPLAY INVISIBLE (12 -13);
FORCEPROP 2 LAST CDS_XR_PAGE_TITLE CR-54 : @T6G_MB_LIB.T6G(SCH_1):PAGE54
J 0
(-7890 5250);
DISPLAY 0.638298 (-7890 5250);
PAINT PINK (-7890 5250);
DISPLAY INVISIBLE (-7890 5250);
FORCEADD DNS..2
(-7975 600);
PAINT RED (-7975 600);
FORCEPROP 2 LAST CDS_LIB mstr_misc
J 0
(-7975 600);
DISPLAY INVISIBLE (-7975 600);
FORCEPROP 1 LAST COMMENT_BODY TRUE
J 0
(-7975 600);
PAINT RED (-7975 600);
DISPLAY INVISIBLE (-7975 600);
WIRE 16 -1 (-5650 1375)(-5400 1375);
WIRE 16 -1 (-5650 1375)(-5650 1275);
WIRE 16 -1 (-8750 4925)(-8750 4950);
WIRE 16 -1 (-8625 4375)(-8625 4325);
WIRE 16 -1 (-8750 4375)(-8750 4325);
WIRE 16 -1 (-6725 525)(-6725 375);
WIRE 16 -1 (-7000 525)(-7000 375);
WIRE 16 -1 (-7300 525)(-7300 375);
WIRE 16 -1 (-7625 525)(-7625 375);
WIRE 16 -1 (-7950 525)(-7950 375);
WIRE 16 -1 (-8275 525)(-8275 375);
WIRE 16 -1 (-6150 5925)(-5400 5925);
FORCEPROP 2 LAST SIG_NAME FM_P1_PCC0_N
J 0
(-6110 5935);
DISPLAY 0.489362 (-6110 5935);
WIRE 16 -1 (-6150 5475)(-5400 5475);
FORCEPROP 2 LAST SIG_NAME SVID_PVDDCR_CPU1_P1_SVTO
J 0
(-6125 5485);
DISPLAY 0.489362 (-6125 5485);
WIRE 16 -1 (-600 5825)(-1350 5825);
FORCEPROP 2 LAST SIG_NAME CPU1_THERMTRIP_N
J 0
(-1300 5835);
DISPLAY 0.489362 (-1300 5835);
WIRE 16 -1 (-600 5975)(-1350 5975);
FORCEPROP 2 LAST SIG_NAME CPU1_BP2
J 0
(-1300 5985);
DISPLAY 0.489362 (-1300 5985);
WIRE 16 -1 (-600 5875)(-1350 5875);
FORCEPROP 2 LAST SIG_NAME APML_CPU1_ALERT_N
J 0
(-1300 5885);
DISPLAY 0.489362 (-1300 5885);
WIRE 16 -1 (-600 6025)(-1350 6025);
FORCEPROP 2 LAST SIG_NAME CPU1_BP1
J 0
(-1300 6035);
DISPLAY 0.489362 (-1300 6035);
WIRE 16 -1 (-600 6075)(-1350 6075);
FORCEPROP 2 LAST SIG_NAME CPU1_BP0
J 0
(-1300 6085);
DISPLAY 0.489362 (-1300 6085);
WIRE 16 -1 (-400 6075)(-150 6075);
WIRE 16 -1 (-150 6175)(-150 6075);
WIRE 16 -1 (-150 6025)(-150 6075);
WIRE 16 -1 (-400 6025)(-150 6025);
WIRE 16 -1 (-150 5975)(-150 6025);
WIRE 16 -1 (-400 5975)(-150 5975);
WIRE 16 -1 (-150 5925)(-150 5975);
WIRE 16 -1 (-400 5925)(-150 5925);
WIRE 16 -1 (-150 5875)(-150 5925);
WIRE 16 -1 (-400 5875)(-150 5875);
WIRE 16 -1 (-150 5825)(-150 5875);
WIRE 16 -1 (-400 5825)(-150 5825);
WIRE 16 -1 (-150 5775)(-150 5825);
WIRE 16 -1 (-400 5775)(-150 5775);
WIRE 16 -1 (-150 5725)(-150 5775);
WIRE 16 -1 (-400 5725)(-150 5725);
WIRE 16 -1 (-150 5675)(-150 5725);
WIRE 16 -1 (-400 5675)(-150 5675);
WIRE 16 -1 (-150 5625)(-150 5675);
WIRE 16 -1 (-400 5625)(-150 5625);
WIRE 16 -1 (-150 5575)(-150 5625);
WIRE 16 -1 (-400 5575)(-150 5575);
WIRE 16 -1 (-600 5625)(-1350 5625);
FORCEPROP 2 LAST SIG_NAME CPU1_XTRIG_L7
J 0
(-1300 5635);
DISPLAY 0.489362 (-1300 5635);
WIRE 16 -1 (-1350 5575)(-600 5575);
FORCEPROP 2 LAST SIG_NAME CPU1_PROCHOT_N
J 0
(-1300 5585);
DISPLAY 0.489362 (-1300 5585);
WIRE 16 -1 (-600 5675)(-1350 5675);
FORCEPROP 2 LAST SIG_NAME CPU1_XTRIG_L6
J 0
(-1300 5685);
DISPLAY 0.489362 (-1300 5685);
WIRE 16 -1 (-600 5775)(-1350 5775);
FORCEPROP 2 LAST SIG_NAME CPU1_XTRIG_L4
J 0
(-1300 5785);
DISPLAY 0.489362 (-1300 5785);
WIRE 16 -1 (-600 5725)(-1350 5725);
FORCEPROP 2 LAST SIG_NAME CPU1_XTRIG_L5
J 0
(-1300 5735);
DISPLAY 0.489362 (-1300 5735);
WIRE 16 -1 (-8275 725)(-8275 1125);
WIRE 16 -1 (-8275 1225)(-8275 1125);
WIRE 16 -1 (-8850 1125)(-8275 1125);
FORCEPROP 2 LAST SIG_NAME JTAG_CPU1_TDO
J 0
(-8785 1135);
DISPLAY 0.489362 (-8785 1135);
WIRE 16 -1 (-9050 3075)(-9050 3025);
WIRE 16 -1 (-9050 3075)(-8850 3075);
WIRE 16 -1 (-9050 3125)(-9050 3075);
WIRE 16 -1 (-9050 3025)(-8850 3025);
WIRE 16 -1 (-9050 3125)(-8850 3125);
WIRE 16 -1 (-9050 3175)(-9050 3125);
WIRE 16 -1 (-9050 3175)(-8850 3175);
WIRE 16 -1 (-9050 3225)(-9050 3175);
WIRE 16 -1 (-9050 3225)(-8850 3225);
WIRE 16 -1 (-9050 3275)(-9050 3225);
WIRE 16 -1 (-9050 3275)(-8850 3275);
WIRE 16 -1 (-9050 3325)(-9050 3275);
WIRE 16 -1 (-8850 3325)(-9050 3325);
WIRE 16 -1 (-9050 3550)(-9050 3325);
WIRE 16 -1 (-8275 1500)(-7950 1500);
WIRE 16 -1 (-8275 1550)(-8275 1500);
WIRE 16 -1 (-8275 1500)(-8275 1425);
WIRE 16 -1 (-7950 1500)(-7625 1500);
WIRE 16 -1 (-7950 1425)(-7950 1500);
WIRE 16 -1 (-7625 1500)(-7300 1500);
WIRE 16 -1 (-7625 1425)(-7625 1500);
WIRE 16 -1 (-7300 1500)(-7000 1500);
WIRE 16 -1 (-7300 1425)(-7300 1500);
WIRE 16 -1 (-7000 1500)(-6725 1500);
WIRE 16 -1 (-7000 1500)(-7000 1425);
WIRE 16 -1 (-6725 1500)(-6725 1425);
WIRE 16 -1 (-8750 4650)(-7950 4650);
FORCEPROP 2 LAST SIG_NAME CPU1_SA0
J 0
(-8335 4660);
DISPLAY 0.489362 (-8335 4660);
WIRE 16 -1 (-8750 4725)(-8750 4650);
WIRE 16 -1 (-8750 4650)(-8750 4575);
WIRE 16 -1 (-8625 4600)(-7950 4600);
FORCEPROP 2 LAST SIG_NAME CPU1_SA1
J 0
(-8335 4610);
DISPLAY 0.489362 (-8335 4610);
WIRE 16 -1 (-8625 4600)(-8625 4575);
WIRE 16 -1 (-8650 3325)(-7800 3325);
FORCEPROP 2 LAST SIG_NAME CPU1_SP5R1
J 0
(-8300 3335);
DISPLAY 0.489362 (-8300 3335);
WIRE 16 -1 (-8650 3275)(-7800 3275);
FORCEPROP 2 LAST SIG_NAME CPU1_SP5R2
J 0
(-8300 3285);
DISPLAY 0.489362 (-8300 3285);
WIRE 16 -1 (-8650 3225)(-7800 3225);
FORCEPROP 2 LAST SIG_NAME CPU1_SP5R3
J 0
(-8300 3235);
DISPLAY 0.489362 (-8300 3235);
WIRE 16 -1 (-8650 3175)(-7800 3175);
FORCEPROP 2 LAST SIG_NAME CPU1_SP5R4
J 0
(-8300 3185);
DISPLAY 0.489362 (-8300 3185);
WIRE 16 -1 (-8650 3125)(-7800 3125);
FORCEPROP 2 LAST SIG_NAME CPU1_CORETYPE0
J 0
(-8300 3135);
DISPLAY 0.489362 (-8300 3135);
WIRE 16 -1 (-8650 3075)(-7800 3075);
FORCEPROP 2 LAST SIG_NAME CPU1_CORETYPE1
J 0
(-8300 3085);
DISPLAY 0.489362 (-8300 3085);
WIRE 16 -1 (-7800 3025)(-8650 3025);
FORCEPROP 2 LAST SIG_NAME CPU1_CORETYPE2
J 0
(-8300 3035);
DISPLAY 0.489362 (-8300 3035);
WIRE 16 -1 (-8850 975)(-7300 975);
FORCEPROP 2 LAST SIG_NAME JTAG_CPU1_TCK
J 0
(-8785 985);
DISPLAY 0.489362 (-8785 985);
WIRE 16 -1 (-7300 1225)(-7300 975);
WIRE 16 -1 (-7300 725)(-7300 975);
WIRE 16 -1 (-8850 1075)(-7950 1075);
FORCEPROP 2 LAST SIG_NAME JTAG_CPU1_TDI
J 0
(-8785 1085);
DISPLAY 0.489362 (-8785 1085);
WIRE 16 -1 (-7950 1225)(-7950 1075);
WIRE 16 -1 (-7950 725)(-7950 1075);
WIRE 16 -1 (-8850 1025)(-7625 1025);
FORCEPROP 2 LAST SIG_NAME JTAG_CPU1_TRST_N
J 0
(-8785 1035);
DISPLAY 0.489362 (-8785 1035);
WIRE 16 -1 (-7625 1225)(-7625 1025);
WIRE 16 -1 (-7625 725)(-7625 1025);
WIRE 16 -1 (-8850 875)(-6725 875);
FORCEPROP 2 LAST SIG_NAME JTAG_CPU1_DBREQ_N
J 0
(-8785 885);
DISPLAY 0.489362 (-8785 885);
WIRE 16 -1 (-6725 875)(-6725 1225);
WIRE 16 -1 (-6725 725)(-6725 875);
WIRE 16 -1 (-8850 925)(-7000 925);
FORCEPROP 2 LAST SIG_NAME JTAG_CPU1_TMS
J 0
(-8785 935);
DISPLAY 0.489362 (-8785 935);
WIRE 16 -1 (-7000 1225)(-7000 925);
WIRE 16 -1 (-7000 725)(-7000 925);
WIRE 16 -1 (-6525 3475)(-5400 3475);
FORCEPROP 2 LAST SIG_NAME TP_CPU1_TEST50_IOD
J 0
(-6285 3485);
DISPLAY 0.489362 (-6285 3485);
FORCEPROP 2 LASTPROP $XRERR UNIQUE?
J 0
(-6765 3475);
DISPLAY 0.638298 (-6765 3475);
PAINT MONO (-6765 3475);
DISPLAY INVISIBLE (-6765 3475);
WIRE 16 -1 (-5400 2575)(-6900 2575);
FORCEPROP 2 LAST SIG_NAME VSENSE_VSS_SENSE_A_P1
J 2
(-5645 2585);
DISPLAY 0.489362 (-5645 2585);
WIRE 16 -1 (-6900 2575)(-6975 2575);
WIRE 16 -1 (-6900 2575)(-6900 1950);
WIRE 16 -1 (-6825 1950)(-6825 2525);
WIRE 16 -1 (-5400 2525)(-6825 2525);
FORCEPROP 2 LAST SIG_NAME VSENSE_VSS_SENSE_B_P1
J 0
(-6120 2535);
DISPLAY 0.489362 (-6120 2535);
WIRE 16 -1 (-6825 2525)(-6975 2525);
WIRE 16 -1 (-6750 1950)(-6750 2475);
WIRE 16 -1 (-5400 2475)(-6750 2475);
FORCEPROP 2 LAST SIG_NAME VSENSE_VSS_SENSE_C_P1
J 2
(-5645 2485);
DISPLAY 0.489362 (-5645 2485);
WIRE 16 -1 (-6750 2475)(-6975 2475);
WIRE 16 -1 (-5400 2425)(-6675 2425);
FORCEPROP 2 LAST SIG_NAME VSENSE_PVDD18_S5_P1_DN
J 2
(-5620 2435);
DISPLAY 0.489362 (-5620 2435);
WIRE 16 -1 (-6675 2425)(-6975 2425);
WIRE 16 -1 (-6675 2425)(-6675 1950);
WIRE 16 -1 (-5400 2325)(-6550 2325);
FORCEPROP 2 LAST SIG_NAME VSENSE_PVDDIO_P1_DP
J 0
(-6120 2335);
DISPLAY 0.489362 (-6120 2335);
WIRE 16 -1 (-6550 2325)(-6975 2325);
WIRE 16 -1 (-6550 2325)(-6550 1950);
WIRE 16 -1 (-5400 2175)(-6325 2175);
FORCEPROP 2 LAST SIG_NAME VSENSE_PVDD11_S3_P1_DP
J 2
(-5620 2185);
DISPLAY 0.489362 (-5620 2185);
WIRE 16 -1 (-6325 2175)(-6975 2175);
WIRE 16 -1 (-6325 2175)(-6325 1950);
WIRE 16 -1 (-5400 2075)(-6225 2075);
FORCEPROP 2 LAST SIG_NAME VSENSE_PVDD18_S5_P1_DP
J 2
(-5620 2085);
DISPLAY 0.489362 (-5620 2085);
WIRE 16 -1 (-6225 2075)(-6975 2075);
WIRE 16 -1 (-6225 2075)(-6225 1950);
WIRE 16 -1 (-6150 2125)(-5400 2125);
FORCEPROP 2 LAST SIG_NAME TP_VSENSE_PVDD33_S5_P1
J 0
(-6135 2135);
DISPLAY 0.489362 (-6135 2135);
FORCEPROP 2 LASTPROP $XRERR UNIQUE?
J 0
(-6390 2125);
DISPLAY 0.638298 (-6390 2125);
PAINT MONO (-6390 2125);
DISPLAY INVISIBLE (-6390 2125);
WIRE 16 -1 (-6975 2025)(-6150 2025);
WIRE 16 -1 (-5400 2025)(-6150 2025);
FORCEPROP 2 LAST SIG_NAME VSENSE_PVDDCR_SOC_P1_DP
J 2
(-5595 2035);
DISPLAY 0.489362 (-5595 2035);
WIRE 16 -1 (-6150 1950)(-6150 2025);
WIRE 16 -1 (-5400 2275)(-6475 2275);
FORCEPROP 2 LAST SIG_NAME VSENSE_PVDDCR_CPU1_P1_DP
J 0
(-6120 2285);
DISPLAY 0.489362 (-6120 2285);
WIRE 16 -1 (-6475 2275)(-6975 2275);
WIRE 16 -1 (-6475 2275)(-6475 1950);
WIRE 16 -1 (-5400 2225)(-6400 2225);
FORCEPROP 2 LAST SIG_NAME VSENSE_PVDDCR_CPU0_P1_DP
J 2
(-5570 2235);
DISPLAY 0.489362 (-5570 2235);
WIRE 16 -1 (-6400 2225)(-6975 2225);
WIRE 16 -1 (-6400 2225)(-6400 1950);
WIRE 16 -1 (-6525 4075)(-5400 4075);
FORCEPROP 2 LAST SIG_NAME TP_CPU1_TEST47_CCD0
J 0
(-6285 4085);
DISPLAY 0.489362 (-6285 4085);
FORCEPROP 2 LASTPROP $XRERR UNIQUE?
J 0
(-6765 4075);
DISPLAY 0.638298 (-6765 4075);
PAINT MONO (-6765 4075);
DISPLAY INVISIBLE (-6765 4075);
WIRE 16 -1 (-6525 4025)(-5400 4025);
FORCEPROP 2 LAST SIG_NAME TP_CPU1_TEST47_CCD1
J 0
(-6285 4035);
DISPLAY 0.489362 (-6285 4035);
FORCEPROP 2 LASTPROP $XRERR UNIQUE?
J 0
(-6765 4025);
DISPLAY 0.638298 (-6765 4025);
PAINT MONO (-6765 4025);
DISPLAY INVISIBLE (-6765 4025);
WIRE 16 -1 (-6525 3975)(-5400 3975);
FORCEPROP 2 LAST SIG_NAME TP_CPU1_TEST47_CCD2
J 0
(-6285 3985);
DISPLAY 0.489362 (-6285 3985);
FORCEPROP 2 LASTPROP $XRERR UNIQUE?
J 0
(-6765 3975);
DISPLAY 0.638298 (-6765 3975);
PAINT MONO (-6765 3975);
DISPLAY INVISIBLE (-6765 3975);
WIRE 16 -1 (-6525 3825)(-5400 3825);
FORCEPROP 2 LAST SIG_NAME TP_CPU1_TEST47_IOD0
J 0
(-6285 3835);
DISPLAY 0.489362 (-6285 3835);
FORCEPROP 2 LASTPROP $XRERR UNIQUE?
J 0
(-6765 3825);
DISPLAY 0.638298 (-6765 3825);
PAINT MONO (-6765 3825);
DISPLAY INVISIBLE (-6765 3825);
WIRE 16 -1 (-6525 3775)(-5400 3775);
FORCEPROP 2 LAST SIG_NAME TP_CPU1_TEST47_IOD1
J 0
(-6285 3785);
DISPLAY 0.489362 (-6285 3785);
FORCEPROP 2 LASTPROP $XRERR UNIQUE?
J 0
(-6765 3775);
DISPLAY 0.638298 (-6765 3775);
PAINT MONO (-6765 3775);
DISPLAY INVISIBLE (-6765 3775);
WIRE 16 -1 (-6525 3925)(-5400 3925);
FORCEPROP 2 LAST SIG_NAME TP_CPU1_TEST47_CCD3
J 0
(-6285 3935);
DISPLAY 0.489362 (-6285 3935);
FORCEPROP 2 LASTPROP $XRERR UNIQUE?
J 0
(-6765 3925);
DISPLAY 0.638298 (-6765 3925);
PAINT MONO (-6765 3925);
DISPLAY INVISIBLE (-6765 3925);
WIRE 16 -1 (-6600 3325)(-5400 3325);
FORCEPROP 2 LAST SIG_NAME PRSNT_CPU1_N
J 2
(-6210 3335);
DISPLAY 0.489362 (-6210 3335);
WIRE 16 -1 (-6600 3225)(-5400 3225);
FORCEPROP 2 LAST SIG_NAME CPU1_SA0
J 0
(-6485 3235);
DISPLAY 0.489362 (-6485 3235);
WIRE 16 -1 (-6600 3175)(-5400 3175);
FORCEPROP 2 LAST SIG_NAME CPU1_SA1
J 0
(-6485 3185);
DISPLAY 0.489362 (-6485 3185);
WIRE 16 -1 (-6600 3025)(-5400 3025);
FORCEPROP 2 LAST SIG_NAME CPU1_SP5R1
J 2
(-6260 3035);
DISPLAY 0.489362 (-6260 3035);
WIRE 16 -1 (-6600 2975)(-5400 2975);
FORCEPROP 2 LAST SIG_NAME CPU1_SP5R2
J 2
(-6260 2985);
DISPLAY 0.489362 (-6260 2985);
WIRE 16 -1 (-6600 2875)(-5400 2875);
FORCEPROP 2 LAST SIG_NAME CPU1_SP5R4
J 2
(-6260 2885);
DISPLAY 0.489362 (-6260 2885);
WIRE 16 -1 (-6600 2925)(-5400 2925);
FORCEPROP 2 LAST SIG_NAME CPU1_SP5R3
J 2
(-6260 2935);
DISPLAY 0.489362 (-6260 2935);
WIRE 16 -1 (-6600 2775)(-5400 2775);
FORCEPROP 2 LAST SIG_NAME CPU1_CORETYPE0
J 2
(-6160 2785);
DISPLAY 0.489362 (-6160 2785);
WIRE 16 -1 (-6600 2725)(-5400 2725);
FORCEPROP 2 LAST SIG_NAME CPU1_CORETYPE1
J 2
(-6160 2735);
DISPLAY 0.489362 (-6160 2735);
WIRE 16 -1 (-6600 2675)(-5400 2675);
FORCEPROP 2 LAST SIG_NAME CPU1_CORETYPE2
J 2
(-6160 2685);
DISPLAY 0.489362 (-6160 2685);
WIRE 16 -1 (-7825 5725)(-6875 5725);
FORCEPROP 2 LAST SIG_NAME SVID_PVDDCR_CPU0_P1_SVD_R
J 0
(-7600 5735);
DISPLAY 0.489362 (-7600 5735);
WIRE 16 -1 (-6875 5775)(-7825 5775);
FORCEPROP 2 LAST SIG_NAME SVID_PVDDCR_CPU0_P1_SVC_R
J 0
(-7600 5785);
DISPLAY 0.489362 (-7600 5785);
WIRE 16 -1 (-7825 5525)(-6875 5525);
FORCEPROP 2 LAST SIG_NAME SVID_PVDDCR_CPU1_P1_SVD_R
J 0
(-7600 5535);
DISPLAY 0.489362 (-7600 5535);
WIRE 16 -1 (-6875 5575)(-7825 5575);
FORCEPROP 2 LAST SIG_NAME SVID_PVDDCR_CPU1_P1_SVC_R
J 0
(-7600 5585);
DISPLAY 0.489362 (-7600 5585);
WIRE 16 -1 (-6800 4825)(-6200 4825);
FORCEPROP 2 LAST SIG_NAME JTAG_CPU1_TDO
J 0
(-6725 4835);
DISPLAY 0.489362 (-6725 4835);
WIRE 16 -1 (-6675 5725)(-5400 5725);
FORCEPROP 2 LAST SIG_NAME SVID_PVDDCR_CPU0_P1_SVD
J 0
(-6125 5735);
DISPLAY 0.489362 (-6125 5735);
FORCEPROP 2 LASTPROP $XRERR UNIQUE?
J 0
(-6365 5735);
DISPLAY 0.638298 (-6365 5735);
PAINT MONO (-6365 5735);
DISPLAY INVISIBLE (-6365 5735);
WIRE 16 -1 (-6675 5525)(-5400 5525);
FORCEPROP 2 LAST SIG_NAME SVID_PVDDCR_CPU1_P1_SVD
J 0
(-6125 5535);
DISPLAY 0.489362 (-6125 5535);
FORCEPROP 2 LASTPROP $XRERR UNIQUE?
J 0
(-6365 5535);
DISPLAY 0.638298 (-6365 5535);
PAINT MONO (-6365 5535);
DISPLAY INVISIBLE (-6365 5535);
WIRE 16 -1 (-6675 5775)(-5400 5775);
FORCEPROP 2 LAST SIG_NAME SVID_PVDDCR_CPU0_P1_SVC
J 0
(-6125 5785);
DISPLAY 0.489362 (-6125 5785);
FORCEPROP 2 LASTPROP $XRERR UNIQUE?
J 0
(-6365 5785);
DISPLAY 0.638298 (-6365 5785);
PAINT MONO (-6365 5785);
DISPLAY INVISIBLE (-6365 5785);
WIRE 16 -1 (-6675 5575)(-5400 5575);
FORCEPROP 2 LAST SIG_NAME SVID_PVDDCR_CPU1_P1_SVC
J 0
(-6125 5585);
DISPLAY 0.489362 (-6125 5585);
FORCEPROP 2 LASTPROP $XRERR UNIQUE?
J 0
(-6365 5585);
DISPLAY 0.638298 (-6365 5585);
PAINT MONO (-6365 5585);
DISPLAY INVISIBLE (-6365 5585);
WIRE 16 -1 (-6150 5875)(-5400 5875);
FORCEPROP 2 LAST SIG_NAME FM_P1_PCC1_N
J 0
(-6110 5885);
DISPLAY 0.489362 (-6110 5885);
WIRE 16 -1 (-6150 5675)(-5400 5675);
FORCEPROP 2 LAST SIG_NAME SVID_PVDDCR_CPU0_P1_SVTO
J 0
(-6125 5685);
DISPLAY 0.489362 (-6125 5685);
WIRE 16 -1 (-6800 4775)(-5400 4775);
FORCEPROP 2 LAST SIG_NAME JTAG_CPU1_TDI
J 0
(-6725 4785);
DISPLAY 0.489362 (-6725 4785);
WIRE 16 -1 (-6800 4725)(-5400 4725);
FORCEPROP 2 LAST SIG_NAME JTAG_CPU1_TRST_N
J 0
(-6725 4735);
DISPLAY 0.489362 (-6725 4735);
WIRE 16 -1 (-6800 4675)(-5400 4675);
FORCEPROP 2 LAST SIG_NAME JTAG_CPU1_TCK
J 0
(-6725 4685);
DISPLAY 0.489362 (-6725 4685);
WIRE 16 -1 (-6800 4625)(-5400 4625);
FORCEPROP 2 LAST SIG_NAME JTAG_CPU1_TMS
J 0
(-6725 4635);
DISPLAY 0.489362 (-6725 4635);
WIRE 16 -1 (-6800 4525)(-5400 4525);
FORCEPROP 2 LAST SIG_NAME JTAG_CPU1_DBREQ_N
J 0
(-6725 4535);
DISPLAY 0.489362 (-6725 4535);
WIRE 16 -1 (-6000 4825)(-5400 4825);
FORCEPROP 2 LAST SIG_NAME JTAG_CPU1_R_TDO
J 0
(-5935 4835);
DISPLAY 0.489362 (-5935 4835);
FORCEPROP 2 LASTPROP $XRERR UNIQUE?
J 0
(-6175 4835);
DISPLAY 0.638298 (-6175 4835);
PAINT MONO (-6175 4835);
DISPLAY INVISIBLE (-6175 4835);
WIRE 16 -1 (-6050 5075)(-5400 5075);
FORCEPROP 2 LAST SIG_NAME SMB_APML_CPU1_SDA
J 2
(-5585 5085);
DISPLAY 0.489362 (-5585 5085);
WIRE 16 -1 (-6050 5125)(-5400 5125);
FORCEPROP 2 LAST SIG_NAME SMB_APML_CPU1_SCL
J 2
(-5585 5135);
DISPLAY 0.489362 (-5585 5135);
WIRE 16 -1 (-3900 1775)(-3125 1775);
FORCEPROP 2 LAST SIG_NAME TP_CPU1_UART0_INTR
J 0
(-3650 1785);
DISPLAY 0.489362 (-3650 1785);
FORCEPROP 2 LASTPROP $XRERR UNIQUE?
J 0
(-3095 1775);
DISPLAY 0.638298 (-3095 1775);
PAINT MONO (-3095 1775);
DISPLAY INVISIBLE (-3095 1775);
WIRE 16 -1 (-3900 1975)(-3125 1975);
FORCEPROP 2 LAST SIG_NAME TP_CPU1_TEST5_IOD
J 0
(-3665 1985);
DISPLAY 0.489362 (-3665 1985);
FORCEPROP 2 LASTPROP $XRERR UNIQUE?
J 0
(-3095 1975);
DISPLAY 0.638298 (-3095 1975);
PAINT MONO (-3095 1975);
DISPLAY INVISIBLE (-3095 1975);
WIRE 16 -1 (-3900 1375)(-3125 1375);
FORCEPROP 2 LAST SIG_NAME TP_CPU1_TEST41_IOD
J 0
(-3665 1385);
DISPLAY 0.489362 (-3665 1385);
FORCEPROP 2 LASTPROP $XRERR UNIQUE?
J 0
(-3095 1375);
DISPLAY 0.638298 (-3095 1375);
PAINT MONO (-3095 1375);
DISPLAY INVISIBLE (-3095 1375);
WIRE 16 -1 (-3900 1675)(-2775 1675);
FORCEPROP 2 LAST SIG_NAME TP_CPU1_UART0_RX
J 0
(-3650 1685);
DISPLAY 0.489362 (-3650 1685);
FORCEPROP 2 LASTPROP $XRERR UNIQUE?
J 0
(-2745 1675);
DISPLAY 0.638298 (-2745 1675);
PAINT MONO (-2745 1675);
DISPLAY INVISIBLE (-2745 1675);
WIRE 16 -1 (-3900 1825)(-2775 1825);
FORCEPROP 2 LAST SIG_NAME TP_CPU1_UART0_RTS_N
J 0
(-3650 1835);
DISPLAY 0.489362 (-3650 1835);
FORCEPROP 2 LASTPROP $XRERR UNIQUE?
J 0
(-2745 1825);
DISPLAY 0.638298 (-2745 1825);
PAINT MONO (-2745 1825);
DISPLAY INVISIBLE (-2745 1825);
WIRE 16 -1 (-3900 1725)(-2775 1725);
FORCEPROP 2 LAST SIG_NAME TP_CPU1_UART0_TX
J 0
(-3650 1735);
DISPLAY 0.489362 (-3650 1735);
FORCEPROP 2 LASTPROP $XRERR UNIQUE?
J 0
(-2745 1725);
DISPLAY 0.638298 (-2745 1725);
PAINT MONO (-2745 1725);
DISPLAY INVISIBLE (-2745 1725);
WIRE 16 -1 (-3900 1875)(-2775 1875);
FORCEPROP 2 LAST SIG_NAME TP_CPU1_UART0_CTS_N
J 0
(-3650 1885);
DISPLAY 0.489362 (-3650 1885);
FORCEPROP 2 LASTPROP $XRERR UNIQUE?
J 0
(-2745 1875);
DISPLAY 0.638298 (-2745 1875);
PAINT MONO (-2745 1875);
DISPLAY INVISIBLE (-2745 1875);
WIRE 16 -1 (-3900 1575)(-2775 1575);
FORCEPROP 2 LAST SIG_NAME TP_CPU1_UART1_RX
J 0
(-3650 1585);
DISPLAY 0.489362 (-3650 1585);
FORCEPROP 2 LASTPROP $XRERR UNIQUE?
J 0
(-2745 1575);
DISPLAY 0.638298 (-2745 1575);
PAINT MONO (-2745 1575);
DISPLAY INVISIBLE (-2745 1575);
WIRE 16 -1 (-3900 2725)(-3125 2725);
FORCEPROP 2 LAST SIG_NAME TP_CPU1_TEST5_CCD0
J 0
(-3665 2735);
DISPLAY 0.489362 (-3665 2735);
FORCEPROP 2 LASTPROP $XRERR UNIQUE?
J 0
(-3095 2725);
DISPLAY 0.638298 (-3095 2725);
PAINT MONO (-3095 2725);
DISPLAY INVISIBLE (-3095 2725);
WIRE 16 -1 (-3900 2675)(-3125 2675);
FORCEPROP 2 LAST SIG_NAME TP_CPU1_TEST5_CCD1
J 0
(-3665 2685);
DISPLAY 0.489362 (-3665 2685);
FORCEPROP 2 LASTPROP $XRERR UNIQUE?
J 0
(-3095 2675);
DISPLAY 0.638298 (-3095 2675);
PAINT MONO (-3095 2675);
DISPLAY INVISIBLE (-3095 2675);
WIRE 16 -1 (-3900 2625)(-3125 2625);
FORCEPROP 2 LAST SIG_NAME TP_CPU1_TEST5_CCD2
J 0
(-3665 2635);
DISPLAY 0.489362 (-3665 2635);
FORCEPROP 2 LASTPROP $XRERR UNIQUE?
J 0
(-3095 2625);
DISPLAY 0.638298 (-3095 2625);
PAINT MONO (-3095 2625);
DISPLAY INVISIBLE (-3095 2625);
WIRE 16 -1 (-3900 2575)(-3125 2575);
FORCEPROP 2 LAST SIG_NAME TP_CPU1_TEST5_CCD3
J 0
(-3665 2585);
DISPLAY 0.489362 (-3665 2585);
FORCEPROP 2 LASTPROP $XRERR UNIQUE?
J 0
(-3095 2575);
DISPLAY 0.638298 (-3095 2575);
PAINT MONO (-3095 2575);
DISPLAY INVISIBLE (-3095 2575);
WIRE 16 -1 (-3125 2075)(-3900 2075);
FORCEPROP 2 LAST SIG_NAME TP_CPU1_TEST4_IOD
J 0
(-3665 2085);
DISPLAY 0.489362 (-3665 2085);
FORCEPROP 2 LASTPROP $XRERR UNIQUE?
J 0
(-3095 2075);
DISPLAY 0.638298 (-3095 2075);
PAINT MONO (-3095 2075);
DISPLAY INVISIBLE (-3095 2075);
WIRE 16 -1 (-3900 2525)(-3125 2525);
FORCEPROP 2 LAST SIG_NAME TP_CPU1_TEST5_CCD4
J 0
(-3665 2535);
DISPLAY 0.489362 (-3665 2535);
FORCEPROP 2 LASTPROP $XRERR UNIQUE?
J 0
(-3095 2525);
DISPLAY 0.638298 (-3095 2525);
PAINT MONO (-3095 2525);
DISPLAY INVISIBLE (-3095 2525);
WIRE 16 -1 (-3900 2475)(-3125 2475);
FORCEPROP 2 LAST SIG_NAME TP_CPU1_TEST5_CCD5
J 0
(-3665 2485);
DISPLAY 0.489362 (-3665 2485);
FORCEPROP 2 LASTPROP $XRERR UNIQUE?
J 0
(-3095 2475);
DISPLAY 0.638298 (-3095 2475);
PAINT MONO (-3095 2475);
DISPLAY INVISIBLE (-3095 2475);
WIRE 16 -1 (-3900 2425)(-3125 2425);
FORCEPROP 2 LAST SIG_NAME TP_CPU1_TEST5_CCD6
J 0
(-3665 2435);
DISPLAY 0.489362 (-3665 2435);
FORCEPROP 2 LASTPROP $XRERR UNIQUE?
J 0
(-3095 2425);
DISPLAY 0.638298 (-3095 2425);
PAINT MONO (-3095 2425);
DISPLAY INVISIBLE (-3095 2425);
WIRE 16 -1 (-3900 2375)(-3125 2375);
FORCEPROP 2 LAST SIG_NAME TP_CPU1_TEST5_CCD7
J 0
(-3665 2385);
DISPLAY 0.489362 (-3665 2385);
FORCEPROP 2 LASTPROP $XRERR UNIQUE?
J 0
(-3095 2375);
DISPLAY 0.638298 (-3095 2375);
PAINT MONO (-3095 2375);
DISPLAY INVISIBLE (-3095 2375);
WIRE 16 -1 (-3900 2325)(-3125 2325);
FORCEPROP 2 LAST SIG_NAME TP_CPU1_TEST5_CCD8
J 0
(-3665 2335);
DISPLAY 0.489362 (-3665 2335);
FORCEPROP 2 LASTPROP $XRERR UNIQUE?
J 0
(-3095 2325);
DISPLAY 0.638298 (-3095 2325);
PAINT MONO (-3095 2325);
DISPLAY INVISIBLE (-3095 2325);
WIRE 16 -1 (-3900 3025)(-3125 3025);
FORCEPROP 2 LAST SIG_NAME TP_CPU1_TEST4_CCD7
J 0
(-3665 3035);
DISPLAY 0.489362 (-3665 3035);
FORCEPROP 2 LASTPROP $XRERR UNIQUE?
J 0
(-3095 3025);
DISPLAY 0.638298 (-3095 3025);
PAINT MONO (-3095 3025);
DISPLAY INVISIBLE (-3095 3025);
WIRE 16 -1 (-3900 2275)(-3125 2275);
FORCEPROP 2 LAST SIG_NAME TP_CPU1_TEST5_CCD9
J 0
(-3665 2285);
DISPLAY 0.489362 (-3665 2285);
FORCEPROP 2 LASTPROP $XRERR UNIQUE?
J 0
(-3095 2275);
DISPLAY 0.638298 (-3095 2275);
PAINT MONO (-3095 2275);
DISPLAY INVISIBLE (-3095 2275);
WIRE 16 -1 (-3900 2975)(-3125 2975);
FORCEPROP 2 LAST SIG_NAME TP_CPU1_TEST4_CCD8
J 0
(-3665 2985);
DISPLAY 0.489362 (-3665 2985);
FORCEPROP 2 LASTPROP $XRERR UNIQUE?
J 0
(-3095 2975);
DISPLAY 0.638298 (-3095 2975);
PAINT MONO (-3095 2975);
DISPLAY INVISIBLE (-3095 2975);
WIRE 16 -1 (-3900 2875)(-3125 2875);
FORCEPROP 2 LAST SIG_NAME TP_CPU1_TEST4_CCD10
J 0
(-3665 2885);
DISPLAY 0.489362 (-3665 2885);
FORCEPROP 2 LASTPROP $XRERR UNIQUE?
J 0
(-3095 2875);
DISPLAY 0.638298 (-3095 2875);
PAINT MONO (-3095 2875);
DISPLAY INVISIBLE (-3095 2875);
WIRE 16 -1 (-3900 2925)(-3125 2925);
FORCEPROP 2 LAST SIG_NAME TP_CPU1_TEST4_CCD9
J 0
(-3665 2935);
DISPLAY 0.489362 (-3665 2935);
FORCEPROP 2 LASTPROP $XRERR UNIQUE?
J 0
(-3095 2925);
DISPLAY 0.638298 (-3095 2925);
PAINT MONO (-3095 2925);
DISPLAY INVISIBLE (-3095 2925);
WIRE 16 -1 (-3125 2225)(-3900 2225);
FORCEPROP 2 LAST SIG_NAME TP_CPU1_TEST5_CCD10
J 0
(-3665 2235);
DISPLAY 0.489362 (-3665 2235);
FORCEPROP 2 LASTPROP $XRERR UNIQUE?
J 0
(-3095 2225);
DISPLAY 0.638298 (-3095 2225);
PAINT MONO (-3095 2225);
DISPLAY INVISIBLE (-3095 2225);
WIRE 16 -1 (-3900 2825)(-3125 2825);
FORCEPROP 2 LAST SIG_NAME TP_CPU1_TEST4_CCD11
J 0
(-3665 2835);
DISPLAY 0.489362 (-3665 2835);
FORCEPROP 2 LASTPROP $XRERR UNIQUE?
J 0
(-3095 2825);
DISPLAY 0.638298 (-3095 2825);
PAINT MONO (-3095 2825);
DISPLAY INVISIBLE (-3095 2825);
WIRE 16 -1 (-3900 2175)(-3125 2175);
FORCEPROP 2 LAST SIG_NAME TP_CPU1_TEST5_CCD11
J 0
(-3665 2185);
DISPLAY 0.489362 (-3665 2185);
FORCEPROP 2 LASTPROP $XRERR UNIQUE?
J 0
(-3095 2175);
DISPLAY 0.638298 (-3095 2175);
PAINT MONO (-3095 2175);
DISPLAY INVISIBLE (-3095 2175);
WIRE 16 -1 (-3900 3625)(-3125 3625);
FORCEPROP 2 LAST SIG_NAME TP_CPU1_TEST6_X3D4
J 0
(-3665 3635);
DISPLAY 0.489362 (-3665 3635);
FORCEPROP 2 LASTPROP $XRERR UNIQUE?
J 0
(-3095 3625);
DISPLAY 0.638298 (-3095 3625);
PAINT MONO (-3095 3625);
DISPLAY INVISIBLE (-3095 3625);
WIRE 16 -1 (-3900 4075)(-3125 4075);
FORCEPROP 2 LAST SIG_NAME TP_CPU1_TEST6_CCD1
J 0
(-3665 4085);
DISPLAY 0.489362 (-3665 4085);
FORCEPROP 2 LASTPROP $XRERR UNIQUE?
J 0
(-3095 4075);
DISPLAY 0.638298 (-3095 4075);
PAINT MONO (-3095 4075);
DISPLAY INVISIBLE (-3095 4075);
WIRE 16 -1 (-3900 3575)(-3125 3575);
FORCEPROP 2 LAST SIG_NAME TP_CPU1_TEST6_X3D5
J 0
(-3665 3585);
DISPLAY 0.489362 (-3665 3585);
FORCEPROP 2 LASTPROP $XRERR UNIQUE?
J 0
(-3095 3575);
DISPLAY 0.638298 (-3095 3575);
PAINT MONO (-3095 3575);
DISPLAY INVISIBLE (-3095 3575);
WIRE 16 -1 (-3900 4025)(-3125 4025);
FORCEPROP 2 LAST SIG_NAME TP_CPU1_TEST6_CCD2
J 0
(-3665 4035);
DISPLAY 0.489362 (-3665 4035);
FORCEPROP 2 LASTPROP $XRERR UNIQUE?
J 0
(-3095 4025);
DISPLAY 0.638298 (-3095 4025);
PAINT MONO (-3095 4025);
DISPLAY INVISIBLE (-3095 4025);
WIRE 16 -1 (-3900 3375)(-3125 3375);
FORCEPROP 2 LAST SIG_NAME TP_CPU1_TEST4_CCD0
J 0
(-3665 3385);
DISPLAY 0.489362 (-3665 3385);
FORCEPROP 2 LASTPROP $XRERR UNIQUE?
J 0
(-3095 3375);
DISPLAY 0.638298 (-3095 3375);
PAINT MONO (-3095 3375);
DISPLAY INVISIBLE (-3095 3375);
WIRE 16 -1 (-3900 3975)(-3125 3975);
FORCEPROP 2 LAST SIG_NAME TP_CPU1_TEST6_CCD3
J 0
(-3665 3985);
DISPLAY 0.489362 (-3665 3985);
FORCEPROP 2 LASTPROP $XRERR UNIQUE?
J 0
(-3095 3975);
DISPLAY 0.638298 (-3095 3975);
PAINT MONO (-3095 3975);
DISPLAY INVISIBLE (-3095 3975);
WIRE 16 -1 (-3900 3325)(-3125 3325);
FORCEPROP 2 LAST SIG_NAME TP_CPU1_TEST4_CCD1
J 0
(-3665 3335);
DISPLAY 0.489362 (-3665 3335);
FORCEPROP 2 LASTPROP $XRERR UNIQUE?
J 0
(-3095 3325);
DISPLAY 0.638298 (-3095 3325);
PAINT MONO (-3095 3325);
DISPLAY INVISIBLE (-3095 3325);
WIRE 16 -1 (-3900 3275)(-3125 3275);
FORCEPROP 2 LAST SIG_NAME TP_CPU1_TEST4_CCD2
J 0
(-3665 3285);
DISPLAY 0.489362 (-3665 3285);
FORCEPROP 2 LASTPROP $XRERR UNIQUE?
J 0
(-3095 3275);
DISPLAY 0.638298 (-3095 3275);
PAINT MONO (-3095 3275);
DISPLAY INVISIBLE (-3095 3275);
WIRE 16 -1 (-3900 3225)(-3125 3225);
FORCEPROP 2 LAST SIG_NAME TP_CPU1_TEST4_CCD3
J 0
(-3665 3235);
DISPLAY 0.489362 (-3665 3235);
FORCEPROP 2 LASTPROP $XRERR UNIQUE?
J 0
(-3095 3225);
DISPLAY 0.638298 (-3095 3225);
PAINT MONO (-3095 3225);
DISPLAY INVISIBLE (-3095 3225);
WIRE 16 -1 (-3900 3475)(-3125 3475);
FORCEPROP 2 LAST SIG_NAME TP_CPU1_TEST6_IOD
J 0
(-3665 3485);
DISPLAY 0.489362 (-3665 3485);
FORCEPROP 2 LASTPROP $XRERR UNIQUE?
J 0
(-3095 3475);
DISPLAY 0.638298 (-3095 3475);
PAINT MONO (-3095 3475);
DISPLAY INVISIBLE (-3095 3475);
WIRE 16 -1 (-3900 3175)(-3125 3175);
FORCEPROP 2 LAST SIG_NAME TP_CPU1_TEST4_CCD4
J 0
(-3665 3185);
DISPLAY 0.489362 (-3665 3185);
FORCEPROP 2 LASTPROP $XRERR UNIQUE?
J 0
(-3095 3175);
DISPLAY 0.638298 (-3095 3175);
PAINT MONO (-3095 3175);
DISPLAY INVISIBLE (-3095 3175);
WIRE 16 -1 (-3900 3125)(-3125 3125);
FORCEPROP 2 LAST SIG_NAME TP_CPU1_TEST4_CCD5
J 0
(-3665 3135);
DISPLAY 0.489362 (-3665 3135);
FORCEPROP 2 LASTPROP $XRERR UNIQUE?
J 0
(-3095 3125);
DISPLAY 0.638298 (-3095 3125);
PAINT MONO (-3095 3125);
DISPLAY INVISIBLE (-3095 3125);
WIRE 16 -1 (-3900 3075)(-3125 3075);
FORCEPROP 2 LAST SIG_NAME TP_CPU1_TEST4_CCD6
J 0
(-3665 3085);
DISPLAY 0.489362 (-3665 3085);
FORCEPROP 2 LASTPROP $XRERR UNIQUE?
J 0
(-3095 3075);
DISPLAY 0.638298 (-3095 3075);
PAINT MONO (-3095 3075);
DISPLAY INVISIBLE (-3095 3075);
WIRE 16 -1 (-3900 3825)(-3125 3825);
FORCEPROP 2 LAST SIG_NAME TP_CPU1_TEST6_X3D0
J 0
(-3665 3835);
DISPLAY 0.489362 (-3665 3835);
FORCEPROP 2 LASTPROP $XRERR UNIQUE?
J 0
(-3095 3825);
DISPLAY 0.638298 (-3095 3825);
PAINT MONO (-3095 3825);
DISPLAY INVISIBLE (-3095 3825);
WIRE 16 -1 (-3900 3775)(-3125 3775);
FORCEPROP 2 LAST SIG_NAME TP_CPU1_TEST6_X3D1
J 0
(-3665 3785);
DISPLAY 0.489362 (-3665 3785);
FORCEPROP 2 LASTPROP $XRERR UNIQUE?
J 0
(-3095 3775);
DISPLAY 0.638298 (-3095 3775);
PAINT MONO (-3095 3775);
DISPLAY INVISIBLE (-3095 3775);
WIRE 16 -1 (-3900 3725)(-3125 3725);
FORCEPROP 2 LAST SIG_NAME TP_CPU1_TEST6_X3D2
J 0
(-3665 3735);
DISPLAY 0.489362 (-3665 3735);
FORCEPROP 2 LASTPROP $XRERR UNIQUE?
J 0
(-3095 3725);
DISPLAY 0.638298 (-3095 3725);
PAINT MONO (-3095 3725);
DISPLAY INVISIBLE (-3095 3725);
WIRE 16 -1 (-3900 3675)(-3125 3675);
FORCEPROP 2 LAST SIG_NAME TP_CPU1_TEST6_X3D3
J 0
(-3665 3685);
DISPLAY 0.489362 (-3665 3685);
FORCEPROP 2 LASTPROP $XRERR UNIQUE?
J 0
(-3095 3675);
DISPLAY 0.638298 (-3095 3675);
PAINT MONO (-3095 3675);
DISPLAY INVISIBLE (-3095 3675);
WIRE 16 -1 (-1925 2450)(-1300 2450);
FORCEPROP 2 LAST SIG_NAME CPU1_BP3
J 0
(-1710 2460);
DISPLAY 0.489362 (-1710 2460);
WIRE 16 -1 (-1925 2500)(-1300 2500);
FORCEPROP 2 LAST SIG_NAME CPU1_BP2
J 0
(-1710 2510);
DISPLAY 0.489362 (-1710 2510);
WIRE 16 -1 (-1925 2600)(-1300 2600);
FORCEPROP 2 LAST SIG_NAME CPU1_BP0
J 0
(-1710 2610);
DISPLAY 0.489362 (-1710 2610);
WIRE 16 -1 (-1925 2550)(-1300 2550);
FORCEPROP 2 LAST SIG_NAME CPU1_BP1
J 0
(-1710 2560);
DISPLAY 0.489362 (-1710 2560);
WIRE 16 -1 (-1525 3650)(-1975 3650);
FORCEPROP 2 LAST SIG_NAME CPU1_XTRIG_L4
J 0
(-1885 3660);
DISPLAY 0.489362 (-1885 3660);
WIRE 16 -1 (-1525 3600)(-1975 3600);
FORCEPROP 2 LAST SIG_NAME CPU1_XTRIG_L5
J 0
(-1885 3610);
DISPLAY 0.489362 (-1885 3610);
WIRE 16 -1 (-1525 3550)(-1975 3550);
FORCEPROP 2 LAST SIG_NAME CPU1_XTRIG_L6
J 0
(-1885 3560);
DISPLAY 0.489362 (-1885 3560);
WIRE 16 -1 (-1525 3500)(-1975 3500);
FORCEPROP 2 LAST SIG_NAME CPU1_XTRIG_L7
J 0
(-1885 3510);
DISPLAY 0.489362 (-1885 3510);
WIRE 16 -1 (-775 3600)(-1325 3600);
FORCEPROP 2 LAST SIG_NAME CPU1_XTRIG_R1_L5
J 0
(-1185 3610);
DISPLAY 0.489362 (-1185 3610);
FORCEPROP 2 LASTPROP $XRERR UNIQUE?
J 0
(-1425 3610);
DISPLAY 0.638298 (-1425 3610);
PAINT MONO (-1425 3610);
DISPLAY INVISIBLE (-1425 3610);
WIRE 16 -1 (-775 3650)(-1325 3650);
FORCEPROP 2 LAST SIG_NAME CPU1_XTRIG_R1_L4
J 0
(-1185 3660);
DISPLAY 0.489362 (-1185 3660);
FORCEPROP 2 LASTPROP $XRERR UNIQUE?
J 0
(-1425 3660);
DISPLAY 0.638298 (-1425 3660);
PAINT MONO (-1425 3660);
DISPLAY INVISIBLE (-1425 3660);
WIRE 16 -1 (-775 3500)(-1325 3500);
FORCEPROP 2 LAST SIG_NAME CPU1_XTRIG_R1_L7
J 0
(-1185 3510);
DISPLAY 0.489362 (-1185 3510);
FORCEPROP 2 LASTPROP $XRERR UNIQUE?
J 0
(-1425 3510);
DISPLAY 0.638298 (-1425 3510);
PAINT MONO (-1425 3510);
DISPLAY INVISIBLE (-1425 3510);
WIRE 16 -1 (-775 3550)(-1325 3550);
FORCEPROP 2 LAST SIG_NAME CPU1_XTRIG_R1_L6
J 0
(-1185 3560);
DISPLAY 0.489362 (-1185 3560);
FORCEPROP 2 LASTPROP $XRERR UNIQUE?
J 0
(-1425 3560);
DISPLAY 0.638298 (-1425 3560);
PAINT MONO (-1425 3560);
DISPLAY INVISIBLE (-1425 3560);
WIRE 16 -1 (-750 2600)(-675 2600);
WIRE 16 -1 (-675 2600)(-675 2550);
WIRE 16 -1 (-750 2550)(-675 2550);
WIRE 16 -1 (-675 2550)(-675 2500);
WIRE 16 -1 (-675 2500)(-675 2450);
WIRE 16 -1 (-750 2500)(-675 2500);
WIRE 16 -1 (-750 2450)(-675 2450);
WIRE 16 -1 (-675 2450)(-675 2350);
WIRE 16 -1 (-225 3650)(-150 3650);
WIRE 16 -1 (-150 3650)(-150 3600);
WIRE 16 -1 (-225 3600)(-150 3600);
WIRE 16 -1 (-150 3600)(-150 3550);
WIRE 16 -1 (-150 3550)(-150 3500);
WIRE 16 -1 (-225 3550)(-150 3550);
WIRE 16 -1 (-225 3500)(-150 3500);
WIRE 16 -1 (-150 3500)(-150 3400);
WIRE 16 -1 (-3900 4975)(-3200 4975);
FORCEPROP 2 LAST SIG_NAME CPU1_THERMTRIP_N
J 0
(-3700 4985);
DISPLAY 0.489362 (-3700 4985);
FORCEPROP 2 LASTPROP $XR0 54 
J 0
(-3795 4985);
DISPLAY 0.638298 (-3795 4985);
PAINT MONO (-3795 4985);
WIRE 16 -1 (-3900 4825)(-3200 4825);
FORCEPROP 2 LAST SIG_NAME CPU1_XTRIG_R2_L4
J 0
(-3685 4835);
DISPLAY 0.489362 (-3685 4835);
FORCEPROP 2 LASTPROP $XRERR UNIQUE?
J 0
(-3925 4835);
DISPLAY 0.638298 (-3925 4835);
PAINT MONO (-3925 4835);
DISPLAY INVISIBLE (-3925 4835);
WIRE 16 -1 (-3900 4775)(-3200 4775);
FORCEPROP 2 LAST SIG_NAME CPU1_XTRIG_R2_L5
J 0
(-3685 4785);
DISPLAY 0.489362 (-3685 4785);
FORCEPROP 2 LASTPROP $XRERR UNIQUE?
J 0
(-3925 4785);
DISPLAY 0.638298 (-3925 4785);
PAINT MONO (-3925 4785);
DISPLAY INVISIBLE (-3925 4785);
WIRE 16 -1 (-3900 4725)(-3200 4725);
FORCEPROP 2 LAST SIG_NAME CPU1_XTRIG_R2_L6
J 0
(-3685 4735);
DISPLAY 0.489362 (-3685 4735);
FORCEPROP 2 LASTPROP $XRERR UNIQUE?
J 0
(-3925 4735);
DISPLAY 0.638298 (-3925 4735);
PAINT MONO (-3925 4735);
DISPLAY INVISIBLE (-3925 4735);
WIRE 16 -1 (-3900 4675)(-3200 4675);
FORCEPROP 2 LAST SIG_NAME CPU1_XTRIG_R2_L7
J 0
(-3685 4685);
DISPLAY 0.489362 (-3685 4685);
FORCEPROP 2 LASTPROP $XRERR UNIQUE?
J 0
(-3925 4685);
DISPLAY 0.638298 (-3925 4685);
PAINT MONO (-3925 4685);
DISPLAY INVISIBLE (-3925 4685);
WIRE 16 -1 (-3900 4125)(-3125 4125);
FORCEPROP 2 LAST SIG_NAME TP_CPU1_TEST6_CCD0
J 0
(-3665 4135);
DISPLAY 0.489362 (-3665 4135);
FORCEPROP 2 LASTPROP $XRERR UNIQUE?
J 0
(-3095 4125);
DISPLAY 0.638298 (-3095 4125);
PAINT MONO (-3095 4125);
DISPLAY INVISIBLE (-3095 4125);
WIRE 16 -1 (-3900 4425)(-3075 4425);
FORCEPROP 2 LAST SIG_NAME CPU1_BP1
J 0
(-3685 4435);
DISPLAY 0.489362 (-3685 4435);
WIRE 16 -1 (-3900 4475)(-3075 4475);
FORCEPROP 2 LAST SIG_NAME CPU1_BP0
J 0
(-3685 4485);
DISPLAY 0.489362 (-3685 4485);
WIRE 16 -1 (-3900 4375)(-3075 4375);
FORCEPROP 2 LAST SIG_NAME CPU1_BP2
J 0
(-3685 4385);
DISPLAY 0.489362 (-3685 4385);
WIRE 16 -1 (-3900 4325)(-3075 4325);
FORCEPROP 2 LAST SIG_NAME CPU1_BP3
J 0
(-3685 4335);
DISPLAY 0.489362 (-3685 4335);
WIRE 16 -1 (-3900 5125)(-3200 5125);
FORCEPROP 2 LAST SIG_NAME APML_CPU1_ALERT_N
J 0
(-3700 5135);
DISPLAY 0.489362 (-3700 5135);
FORCEPROP 2 LASTPROP $XR0 54 
J 0
(-3795 5135);
DISPLAY 0.638298 (-3795 5135);
PAINT MONO (-3795 5135);
WIRE 16 -1 (-3900 6025)(-3125 6025);
FORCEPROP 2 LAST SIG_NAME NC_CPU1_AZ_BITCLK
J 0
(-3690 6035);
DISPLAY 0.489362 (-3690 6035);
FORCEPROP 2 LASTPROP $XRERR UNIQUE?
J 0
(-3095 6025);
DISPLAY 0.638298 (-3095 6025);
PAINT MONO (-3095 6025);
DISPLAY INVISIBLE (-3095 6025);
WIRE 16 -1 (-3900 5825)(-3125 5825);
FORCEPROP 2 LAST SIG_NAME NC_CPU1_AZ_SDIN2
J 0
(-3690 5835);
DISPLAY 0.489362 (-3690 5835);
FORCEPROP 2 LASTPROP $XRERR UNIQUE?
J 0
(-3095 5825);
DISPLAY 0.638298 (-3095 5825);
PAINT MONO (-3095 5825);
DISPLAY INVISIBLE (-3095 5825);
WIRE 16 -1 (-3900 5775)(-3125 5775);
FORCEPROP 2 LAST SIG_NAME NC_CPU1_AZ_SDOUT
J 0
(-3690 5785);
DISPLAY 0.489362 (-3690 5785);
FORCEPROP 2 LASTPROP $XRERR UNIQUE?
J 0
(-3095 5775);
DISPLAY 0.638298 (-3095 5775);
PAINT MONO (-3095 5775);
DISPLAY INVISIBLE (-3095 5775);
WIRE 16 -1 (-3900 5875)(-3125 5875);
FORCEPROP 2 LAST SIG_NAME NC_CPU1_AZ_SDIN1
J 0
(-3690 5885);
DISPLAY 0.489362 (-3690 5885);
FORCEPROP 2 LASTPROP $XRERR UNIQUE?
J 0
(-3095 5875);
DISPLAY 0.638298 (-3095 5875);
PAINT MONO (-3095 5875);
DISPLAY INVISIBLE (-3095 5875);
WIRE 16 -1 (-3900 5975)(-3125 5975);
FORCEPROP 2 LAST SIG_NAME NC_CPU1_AZ_RST_N
J 0
(-3690 5985);
DISPLAY 0.489362 (-3690 5985);
FORCEPROP 2 LASTPROP $XRERR UNIQUE?
J 0
(-3095 5975);
DISPLAY 0.638298 (-3095 5975);
PAINT MONO (-3095 5975);
DISPLAY INVISIBLE (-3095 5975);
WIRE 16 -1 (-3900 5925)(-3125 5925);
FORCEPROP 2 LAST SIG_NAME NC_CPU1_AZ_SDIN0
J 0
(-3690 5935);
DISPLAY 0.489362 (-3690 5935);
FORCEPROP 2 LASTPROP $XRERR UNIQUE?
J 0
(-3095 5925);
DISPLAY 0.638298 (-3095 5925);
PAINT MONO (-3095 5925);
DISPLAY INVISIBLE (-3095 5925);
WIRE 16 -1 (-3900 5725)(-3125 5725);
FORCEPROP 2 LAST SIG_NAME NC_CPU1_AZ_SYNC
J 0
(-3690 5735);
DISPLAY 0.489362 (-3690 5735);
FORCEPROP 2 LASTPROP $XRERR UNIQUE?
J 0
(-3095 5725);
DISPLAY 0.638298 (-3095 5725);
PAINT MONO (-3095 5725);
DISPLAY INVISIBLE (-3095 5725);
WIRE 16 -1 (-3900 5025)(-2425 5025);
FORCEPROP 2 LAST SIG_NAME CPU1_PROCHOT_N
J 0
(-3700 5035);
DISPLAY 0.489362 (-3700 5035);
WIRE 16 -1 (-3000 4775)(-2425 4775);
FORCEPROP 2 LAST SIG_NAME CPU1_XTRIG_L5
J 0
(-2785 4785);
DISPLAY 0.489362 (-2785 4785);
WIRE 16 -1 (-3000 4725)(-2425 4725);
FORCEPROP 2 LAST SIG_NAME CPU1_XTRIG_L6
J 0
(-2785 4735);
DISPLAY 0.489362 (-2785 4735);
WIRE 16 -1 (-3000 4825)(-2425 4825);
FORCEPROP 2 LAST SIG_NAME CPU1_XTRIG_L4
J 0
(-2785 4835);
DISPLAY 0.489362 (-2785 4835);
WIRE 16 -1 (-3000 4675)(-2425 4675);
FORCEPROP 2 LAST SIG_NAME CPU1_XTRIG_L7
J 0
(-2785 4685);
DISPLAY 0.489362 (-2785 4685);
WIRE 16 -1 (-3000 4975)(-2425 4975);
FORCEPROP 2 LAST SIG_NAME CPU1_THERMTRIP_R_N
J 0
(-2875 4985);
DISPLAY 0.489362 (-2875 4985);
WIRE 16 -1 (-3000 5125)(-2400 5125);
FORCEPROP 2 LAST SIG_NAME APML_CPU1_ALERT_R_N
J 0
(-2850 5135);
DISPLAY 0.489362 (-2850 5135);
WIRE 16 -1 (-600 5925)(-1350 5925);
FORCEPROP 2 LAST SIG_NAME CPU1_BP3
J 0
(-1300 5935);
DISPLAY 0.489362 (-1300 5935);
DOT 1 (-9050 3125);
DOT 1 (-8750 4650);
DOT 1 (-9050 3075);
DOT 1 (-150 3550);
DOT 1 (-150 3500);
DOT 1 (-150 3600);
DOT 1 (-675 2450);
DOT 1 (-675 2550);
DOT 1 (-675 2500);
DOT 1 (-6675 2425);
DOT 1 (-6225 2075);
DOT 1 (-6325 2175);
DOT 1 (-6400 2225);
DOT 1 (-6475 2275);
DOT 1 (-6550 2325);
DOT 1 (-6750 2475);
DOT 1 (-6825 2525);
DOT 1 (-6150 2025);
DOT 1 (-8275 1125);
DOT 1 (-8275 1500);
DOT 1 (-7950 1075);
DOT 1 (-7625 1025);
DOT 1 (-7300 975);
DOT 1 (-7000 925);
DOT 1 (-6725 875);
DOT 1 (-7950 1500);
DOT 1 (-7625 1500);
DOT 1 (-7300 1500);
DOT 1 (-7000 1500);
DOT 1 (-6900 2575);
DOT 1 (-9050 3275);
DOT 1 (-9050 3325);
DOT 1 (-9050 3175);
DOT 1 (-9050 3225);
DOT 1 (-150 6075);
DOT 1 (-150 6025);
DOT 1 (-150 5975);
DOT 1 (-150 5825);
DOT 1 (-150 5875);
DOT 1 (-150 5675);
DOT 1 (-150 5725);
DOT 1 (-150 5625);
DOT 1 (-150 5775);
DOT 1 (-150 5925);
QUIT
